# Altium SchDoc records: 04-PCIe_JTAG.SchDoc
|HEADER=Protel for Windows - Schematic Capture Binary File Version 5.0|Weight=1153|MinorVersion=9
|RECORD=31|FontIdCount=10|Size1=10|FontName1=Times New Roman|Size2=10|Underline2=T|FontName2=Times New Roman|Size3=8|FontName3=Arial|Size4=10|FontName4=Arial|Size5=12|Underline5=T|FontName5=Arial|Size6=11|FontName6=Arial|Size7=24|FontName7=Times New Roman|Size8=12|FontName8=Arial|Size9=7|FontName9=Arial|Size10=7|FontName10=Courier New|UseMBCS=T|IsBOC=T|HotSpotGridOn=T|HotSpotGridSize=4|SheetStyle=12|SystemFont=4|BorderOn=T|SheetNumberSpaceSize=12|AreaColor=16317695|SnapGridOn=T|SnapGridSize=10|VisibleGridOn=T|VisibleGridSize=10|CustomX=2338|CustomX_Frac=58268|CustomY=1653|CustomY_Frac=54331|CustomXZones=8|CustomYZones=6|CustomMarginWidth=19|CustomMarginWidth_Frac=80000|ShowTemplateGraphics=T|TemplateFileName=C:\Users\<user>\Documents\Altium\AD20\Templates\Timecard.SchDot|Display_Unit=0
|RECORD=39|IsNotAccesible=T|OwnerPartId=-1|FileName=C:\Users\<user>\Documents\Altium\AD20\Templates\Timecard.SchDot
|RECORD=4|OwnerIndex=1|OwnerPartId=-1|Location.X=1594|Location.Y=39|Color=8388608|FontID=5|Text=timingcard.com|URL=http://timingcard.com
|RECORD=6|OwnerIndex=1|IndexInSheet=1|OwnerPartId=-1|LocationCount=2|X1=1680|Y1=35|X2=1576|Y2=35
|RECORD=4|OwnerIndex=1|IndexInSheet=2|OwnerPartId=-1|Location.X=1615|Location.Y=27|Justification=4|Color=16711680|FontID=6|Text==SheetNumber
|RECORD=4|OwnerIndex=1|IndexInSheet=3|OwnerPartId=-1|Location.X=1581|Location.X_Frac=42446|Location.Y=29|Location.Y_Frac=96838|Justification=3|FontID=3|Text=SHEET
|RECORD=4|OwnerIndex=1|IndexInSheet=4|OwnerPartId=-1|Location.X=1639|Location.X_Frac=42446|Location.Y=29|Location.Y_Frac=96838|Justification=3|FontID=3|Text=OF
|RECORD=6|OwnerIndex=1|IndexInSheet=5|OwnerPartId=-1|LineWidth=1|LocationCount=2|X1=1679|X1_Frac=42446|Y1=117|Y1_Frac=96838|X2=1576|Y2=118
|RECORD=4|OwnerIndex=1|IndexInSheet=6|OwnerPartId=-1|Location.X=1659|Location.Y=27|Justification=4|Color=16711680|FontID=6|Text==SheetTotal
|RECORD=30|OwnerIndex=1|IndexInSheet=7|OwnerPartId=-1|Location.X=1578|Location.Y=65|Corner.X=1673|Corner.X_Frac=88801|Corner.Y=115|KeepAspect=T|FileName=C:\Users\<user>\Desktop\Timecard Logo\TIMECARD.jpg
|RECORD=6|OwnerIndex=1|IndexInSheet=8|OwnerPartId=-1|LineWidth=1|LocationCount=2|X1=1576|X1_Frac=3162|Y1=117|Y1_Frac=42446|X2=1576|Y2=21
|RECORD=6|OwnerIndex=1|IndexInSheet=9|OwnerPartId=-1|LocationCount=2|X1=1680|Y1=51|X2=1576|Y2=51
|RECORD=4|OwnerIndex=1|IndexInSheet=10|OwnerPartId=-1|Location.X=1581|Location.X_Frac=42446|Location.Y=56|Location.Y_Frac=96838|Justification=3|FontID=3|Text=REV
|RECORD=4|OwnerIndex=1|IndexInSheet=11|OwnerPartId=-1|Location.X=1619|Location.Y=57|Justification=3|FontID=3|Text=DATE
|RECORD=6|OwnerIndex=1|IndexInSheet=12|OwnerPartId=-1|LocationCount=2|X1=1680|Y1=65|X2=1576|Y2=65
|RECORD=4|OwnerIndex=1|IndexInSheet=13|OwnerPartId=-1|Location.X=1605|Location.Y=58|Justification=4|Color=16711680|FontID=6|Text==ProjectRevision
|RECORD=4|OwnerIndex=1|IndexInSheet=14|OwnerPartId=-1|Location.X=1659|Location.Y=58|Justification=4|Color=16711680|FontID=6|Text==ProjectDate
|RECORD=41|IndexInSheet=1|OwnerPartId=-1|Location.X=21474|Location.X_Frac=83647|Location.Y=21464|Location.Y_Frac=83647|Color=8388608|FontID=1|IsHidden=T|Text=01910|Name=Customer
|RECORD=41|IndexInSheet=2|OwnerPartId=-1|Location.X=1000|Location.Y=10|Color=8388608|FontID=1|IsHidden=T|Text=*|Name=DocStatus
|RECORD=17|IndexInSheet=3|OwnerPartId=-1|Style=4|ShowNetName=T|Location.X=740|Location.Y=600|Orientation=3|Color=128|FontID=1|Text=GND
|RECORD=17|IndexInSheet=4|OwnerPartId=-1|Style=4|ShowNetName=T|Location.X=940|Location.Y=600|Orientation=3|Color=128|FontID=1|Text=GND
|RECORD=17|IndexInSheet=5|OwnerPartId=-1|ShowNetName=T|Location.X=670|Location.Y=970|Orientation=1|Color=128|FontID=1|Text=+12V_PCIE
|RECORD=17|IndexInSheet=6|OwnerPartId=-1|ShowNetName=T|Location.X=540|Location.Y=970|Orientation=1|Color=128|FontID=1|Text=+3.3V_PCIE
|RECORD=17|IndexInSheet=7|OwnerPartId=-1|ShowNetName=T|Location.X=1060|Location.Y=920|Orientation=1|Color=128|FontID=1|Text=+3.3V
|RECORD=17|IndexInSheet=8|OwnerPartId=-1|ShowNetName=T|Location.X=1030|Location.Y=940|Orientation=1|Color=128|FontID=1|Text=+3.3V_PCIE
|RECORD=17|IndexInSheet=9|OwnerPartId=-1|ShowNetName=T|Location.X=990|Location.Y=970|Orientation=1|Color=128|FontID=1|Text=+12V_PCIE
|RECORD=22|IndexInSheet=10|OwnerPartId=-1|Location.X=760|Location.Y=910|Color=255|Orientation=1|Symbol=Thin Cross|IsActive=T|SuppressAll=T
|RECORD=22|IndexInSheet=11|OwnerPartId=-1|Location.X=760|Location.Y=900|Color=255|Orientation=1|Symbol=Thin Cross|IsActive=T|SuppressAll=T
|RECORD=22|IndexInSheet=12|OwnerPartId=-1|Location.X=760|Location.Y=850|Color=255|Orientation=1|Symbol=Thin Cross|IsActive=T|SuppressAll=T
|RECORD=17|IndexInSheet=13|OwnerPartId=-1|ShowNetName=T|Location.X=540|Location.Y=810|Orientation=2|Color=255|FontID=1|Text=PCIE_RX0_P|IsCrossSheetConnector=T
|RECORD=17|IndexInSheet=14|OwnerPartId=-1|ShowNetName=T|Location.X=540|Location.Y=800|Orientation=2|Color=255|FontID=1|Text=PCIE_RX0_N|IsCrossSheetConnector=T
|RECORD=17|IndexInSheet=15|OwnerPartId=-1|ShowNetName=T|Location.X=540|Location.Y=760|Orientation=2|Color=255|FontID=1|Text=PCIE_RX1_P|IsCrossSheetConnector=T
|RECORD=17|IndexInSheet=16|OwnerPartId=-1|ShowNetName=T|Location.X=540|Location.Y=750|Orientation=2|Color=255|FontID=1|Text=PCIE_RX1_N|IsCrossSheetConnector=T
|RECORD=17|IndexInSheet=17|OwnerPartId=-1|ShowNetName=T|Location.X=540|Location.Y=720|Orientation=2|Color=255|FontID=1|Text=PCIE_RX2_P|IsCrossSheetConnector=T
|RECORD=17|IndexInSheet=18|OwnerPartId=-1|ShowNetName=T|Location.X=540|Location.Y=710|Orientation=2|Color=255|FontID=1|Text=PCIE_RX2_N|IsCrossSheetConnector=T
|RECORD=17|IndexInSheet=19|OwnerPartId=-1|ShowNetName=T|Location.X=540|Location.Y=680|Orientation=2|Color=255|FontID=1|Text=PCIE_RX3_P|IsCrossSheetConnector=T
|RECORD=17|IndexInSheet=20|OwnerPartId=-1|ShowNetName=T|Location.X=540|Location.Y=670|Orientation=2|Color=255|FontID=1|Text=PCIE_RX3_N|IsCrossSheetConnector=T
|RECORD=17|IndexInSheet=21|OwnerPartId=-1|ShowNetName=T|Location.X=1190|Location.Y=850|Color=255|FontID=1|Text=PCIE_PERST|IsCrossSheetConnector=T
|RECORD=17|IndexInSheet=22|OwnerPartId=-1|ShowNetName=T|Location.X=1190|Location.Y=820|Color=255|FontID=1|Text=PCIE_CLK_P|IsCrossSheetConnector=T
|RECORD=17|IndexInSheet=23|OwnerPartId=-1|ShowNetName=T|Location.X=1190|Location.Y=810|Color=255|FontID=1|Text=PCIE_CLK_N|IsCrossSheetConnector=T
|RECORD=17|IndexInSheet=24|OwnerPartId=-1|ShowNetName=T|Location.X=1190|Location.Y=790|Color=255|FontID=1|Text=PCIE_TX0_P|IsCrossSheetConnector=T
|RECORD=17|IndexInSheet=25|OwnerPartId=-1|ShowNetName=T|Location.X=1190|Location.Y=780|Color=255|FontID=1|Text=PCIE_TX0_N|IsCrossSheetConnector=T
|RECORD=17|IndexInSheet=26|OwnerPartId=-1|ShowNetName=T|Location.X=1190|Location.Y=740|Color=255|FontID=1|Text=PCIE_TX1_P|IsCrossSheetConnector=T
|RECORD=17|IndexInSheet=27|OwnerPartId=-1|ShowNetName=T|Location.X=1190|Location.Y=730|Color=255|FontID=1|Text=PCIE_TX1_N|IsCrossSheetConnector=T
|RECORD=17|IndexInSheet=28|OwnerPartId=-1|ShowNetName=T|Location.X=1190|Location.Y=700|Color=255|FontID=1|Text=PCIE_TX2_P|IsCrossSheetConnector=T
|RECORD=17|IndexInSheet=29|OwnerPartId=-1|ShowNetName=T|Location.X=1190|Location.Y=690|Color=255|FontID=1|Text=PCIE_TX2_N|IsCrossSheetConnector=T
|RECORD=17|IndexInSheet=30|OwnerPartId=-1|ShowNetName=T|Location.X=1190|Location.Y=660|Color=255|FontID=1|Text=PCIE_TX3_P|IsCrossSheetConnector=T
|RECORD=17|IndexInSheet=31|OwnerPartId=-1|ShowNetName=T|Location.X=1190|Location.Y=650|Color=255|FontID=1|Text=PCIE_TX3_N|IsCrossSheetConnector=T
|RECORD=4|IndexInSheet=32|OwnerPartId=-1|Location.X=800|Location.Y=1010|Color=8388608|FontID=7|Text=PCIe Connector
|RECORD=1|LibReference=RES_0603_4.7K|ComponentDescription=RES, 4.7K, 1%, 1/10W, TF, 0603|PartCount=2|DisplayModeCount=1|IndexInSheet=33|OwnerPartId=-1|Location.X=1060|Location.Y=860|Orientation=1|CurrentPartId=1|LibraryPath=*|SourceLibraryName=Resistors.IntLib|TargetFileName=*|AreaColor=11599871|Color=128|PartIDLocked=F|DesignItemId=RES_0603_4.7K|AllPinCount=2
|RECORD=41|OwnerIndex=49|OwnerPartId=-1|Location.X=1056|Location.Y=912|Color=8388608|FontID=8|IsHidden=T|Text=7/25/2013|Name=ModifyDate
|RECORD=41|OwnerIndex=49|IndexInSheet=1|OwnerPartId=-1|Location.X=1056|Location.Y=912|Color=8388608|FontID=8|IsHidden=T|Text=ERJ-3EKF4701V|Name=MFG PART NUM
|RECORD=41|OwnerIndex=49|IndexInSheet=2|OwnerPartId=-1|Location.X=1056|Location.Y=912|Color=8388608|FontID=8|IsHidden=T|Text=PANASONIC|Name=MFG NAME
|RECORD=41|OwnerIndex=49|IndexInSheet=3|OwnerPartId=-1|Location.X=1056|Location.Y=912|Color=8388608|FontID=8|IsHidden=T|Text=RES|Name=CATEGORY
|RECORD=41|OwnerIndex=49|IndexInSheet=4|OwnerPartId=-1|Location.X=1056|Location.Y=912|Color=8388608|FontID=8|IsHidden=T|Text=7/26/2013|Name=Date
|RECORD=41|OwnerIndex=49|IndexInSheet=5|OwnerPartId=-1|Location.X=1056|Location.Y=912|Color=8388608|FontID=8|IsHidden=T|Text=1%|Name=P1
|RECORD=41|OwnerIndex=49|IndexInSheet=6|OwnerPartId=-1|Location.X=1056|Location.Y=912|Color=8388608|FontID=8|IsHidden=T|Text=TF|Name=P3
|RECORD=41|OwnerIndex=49|IndexInSheet=7|OwnerPartId=-1|Location.X=1056|Location.Y=912|Color=8388608|FontID=8|IsHidden=T|Text=1/10W|Name=P2
|RECORD=41|OwnerIndex=49|IndexInSheet=8|OwnerPartId=-1|Location.X=1056|Location.Y=912|Color=8388608|FontID=8|IsHidden=T|Text=125C|Name=MAXTEMP
|RECORD=41|OwnerIndex=49|IndexInSheet=9|OwnerPartId=-1|Location.X=1056|Location.Y=912|Color=8388608|FontID=8|IsHidden=T|Text=-55C|Name=MINTEMP
|RECORD=41|OwnerIndex=49|IndexInSheet=10|OwnerPartId=-1|Location.X=1056|Location.Y=912|Color=8388608|FontID=8|IsHidden=T|Text=100PPM|Name=OTHER
|RECORD=41|OwnerIndex=49|IndexInSheet=11|OwnerPartId=-1|Location.X=1056|Location.Y=912|Color=8388608|FontID=8|IsHidden=T|Text=0603|Name=SIZE
|RECORD=41|OwnerIndex=49|IndexInSheet=12|OwnerPartId=-1|Location.X=1056|Location.Y=912|Color=8388608|FontID=8|IsHidden=T|Text=GENERIC|Name=SUB
|RECORD=41|OwnerIndex=49|IndexInSheet=13|OwnerPartId=-1|Location.X=1056|Location.Y=912|Color=8388608|FontID=8|IsHidden=T|Text=Digi-Key|Name=Supplier 1|ReadOnlyState=3
|RECORD=41|OwnerIndex=49|IndexInSheet=14|OwnerPartId=-1|Location.X=1056|Location.Y=912|Color=8388608|FontID=8|IsHidden=T|Text=P4.70KHCT-ND|Name=Supplier Part Number 1|ReadOnlyState=3
|RECORD=41|OwnerIndex=49|IndexInSheet=15|OwnerPartId=-1|Location.X=1056|Location.Y=912|Color=8388608|FontID=1|IsHidden=T|Text=*|Name=SHEETPART
|RECORD=41|OwnerIndex=49|IndexInSheet=16|OwnerPartId=-1|Location.X=1056|Location.Y=912|Color=8388608|FontID=1|IsHidden=T|Text=RES, 4.7K, 1%, 1/10W, TF, 0603|Name=DESC
|RECORD=41|OwnerIndex=49|IndexInSheet=17|OwnerPartId=-1|Location.X=1064|Location.Y=875|Color=8388608|FontID=8|Text=4.7K|Name=VALUE
|RECORD=2|OwnerIndex=49|OwnerPartId=1|FormalType=1|Electrical=4|PinConglomerate=35|PinLength=10|Location.X=1060|Location.Y=870|Name=1|Designator=1|PinPropagationDelay=0.000000E+000
|RECORD=2|OwnerIndex=49|OwnerPartId=1|FormalType=1|Electrical=4|PinConglomerate=33|PinLength=10|Location.X=1060|Location.Y=900|Name=2|Designator=2|PinPropagationDelay=0.000000E+000
|RECORD=6|OwnerIndex=49|IsNotAccesible=T|IndexInSheet=20|OwnerPartId=1|LineWidth=1|Color=16711680|LocationCount=7|X1=1060|Y1=900|X2=1057|Y2=897|X3=1063|Y3=891|X4=1057|Y4=885|X5=1063|Y5=879|X6=1057|Y6=873|X7=1060|Y7=870
|RECORD=41|OwnerIndex=49|IndexInSheet=21|OwnerPartId=-1|Location.X=1056|Location.Y=912|Color=8388608|FontID=1|IsHidden=T|Text=<VELENTIUM>|Name=VELENTIUM PART NUM
|RECORD=34|OwnerIndex=49|IndexInSheet=-1|OwnerPartId=-1|Location.X=1064|Location.Y=887|Color=8388608|FontID=1|Text=R22|Name=Designator|ReadOnlyState=1
|RECORD=41|OwnerIndex=49|IndexInSheet=-1|OwnerPartId=-1|Location.X=1056|Location.Y=912|Color=8388608|FontID=1|IsHidden=T|Text==MFG PART NUM|Name=Comment
|RECORD=44|OwnerIndex=49
|RECORD=45|OwnerIndex=76|IndexInSheet=-1|Description=Chip Resistor, 0603, 2-Leads, Body 1.57x0.85mm, IPC Medium Density|UseComponentLibrary=T|ModelName=RESC1608X50N|ModelType=PCBLIB|DatafileCount=1|ModelDatafileEntity0=RESC1608X50N|ModelDatafileKind0=PCBLib|IsCurrent=T|DatalinksLocked=T|DatabaseDatalinksLocked=T|IntegratedModel=T|DatabaseModel=T
|RECORD=46|OwnerIndex=77
|RECORD=48|OwnerIndex=77
|RECORD=1|LibReference=CAP_0402_0.1UF_50V|ComponentDescription=CAP, CER, 0.1UF, 50V, 10%, X7R, AEC-Q200, 0402|PartCount=2|DisplayModeCount=1|IndexInSheet=34|OwnerPartId=-1|Location.X=1130|Location.Y=630|Orientation=1|CurrentPartId=1|LibraryPath=*|SourceLibraryName=Capacitors.IntLib|TargetFileName=*|AreaColor=11599871|Color=128|PartIDLocked=F|DesignItemId=CAP_0402_0.1UF_50V|AllPinCount=2
|RECORD=41|OwnerIndex=80|OwnerPartId=-1|Location.X=1078|Location.Y=656|Color=8388608|FontID=8|IsHidden=T|Text=CAP, CER|Name=CATEGORY
|RECORD=41|OwnerIndex=80|IndexInSheet=1|OwnerPartId=-1|Location.X=1078|Location.Y=656|Color=8388608|FontID=8|IsHidden=T|Text=TDK|Name=MFG NAME
|RECORD=41|OwnerIndex=80|IndexInSheet=2|OwnerPartId=-1|Location.X=1078|Location.Y=656|Color=8388608|FontID=8|IsHidden=T|Text=CGA2B3X7R1H104K050BB|Name=MFG PART NUM
|RECORD=41|OwnerIndex=80|IndexInSheet=3|OwnerPartId=-1|Location.X=1078|Location.Y=656|Color=8388608|FontID=8|IsHidden=T|Text=10/23/2013|Name=MODIFY DATE
|RECORD=41|OwnerIndex=80|IndexInSheet=4|OwnerPartId=-1|Location.X=1078|Location.Y=656|Color=8388608|FontID=8|IsHidden=T|Name=Date
|RECORD=41|OwnerIndex=80|IndexInSheet=5|OwnerPartId=-1|Location.X=1078|Location.Y=656|Color=8388608|FontID=8|IsHidden=T|Text=*|Name=SHEETPART
|RECORD=41|OwnerIndex=80|IndexInSheet=6|OwnerPartId=-1|Location.X=1078|Location.Y=656|Color=8388608|FontID=8|IsHidden=T|Text=10%|Name=P1
|RECORD=41|OwnerIndex=80|IndexInSheet=7|OwnerPartId=-1|Location.X=1078|Location.Y=656|Color=8388608|FontID=8|IsHidden=T|Text=125C|Name=MAXTEMP
|RECORD=41|OwnerIndex=80|IndexInSheet=8|OwnerPartId=-1|Location.X=1078|Location.Y=656|Color=8388608|FontID=8|IsHidden=T|Text=-55C|Name=MINTEMP
|RECORD=41|OwnerIndex=80|IndexInSheet=9|OwnerPartId=-1|Location.X=1078|Location.Y=656|Color=8388608|FontID=8|IsHidden=T|Text=AEC-Q200|Name=OTHER
|RECORD=41|OwnerIndex=80|IndexInSheet=10|OwnerPartId=-1|Location.X=1078|Location.Y=656|Color=8388608|FontID=8|IsHidden=T|Text=50V|Name=P2
|RECORD=41|OwnerIndex=80|IndexInSheet=11|OwnerPartId=-1|Location.X=1078|Location.Y=656|Color=8388608|FontID=8|IsHidden=T|Text=X7R|Name=P3
|RECORD=41|OwnerIndex=80|IndexInSheet=12|OwnerPartId=-1|Location.X=1078|Location.Y=656|Color=8388608|FontID=8|IsHidden=T|Text=0402|Name=Size
|RECORD=41|OwnerIndex=80|IndexInSheet=13|OwnerPartId=-1|Location.X=1078|Location.Y=656|Color=8388608|FontID=8|IsHidden=T|Name=SUB
|RECORD=41|OwnerIndex=80|IndexInSheet=14|OwnerPartId=-1|Location.X=1078|Location.Y=656|Color=8388608|FontID=1|IsHidden=T|Text=CAP, CER, 0.1UF, 50V, 10%, X7R, AEC-Q200, 0402|Name=DESC
|RECORD=41|OwnerIndex=80|IndexInSheet=15|OwnerPartId=-1|Location.X=1078|Location.Y=656|Color=8388608|FontID=1|IsHidden=T|Text=Digi-Key|Name=Supplier 1|ReadOnlyState=3
|RECORD=41|OwnerIndex=80|IndexInSheet=16|OwnerPartId=-1|Location.X=1078|Location.Y=656|Color=8388608|FontID=1|IsHidden=T|Text=445-6899-1-ND|Name=Supplier Part Number 1|ReadOnlyState=3
|RECORD=41|OwnerIndex=80|IndexInSheet=17|OwnerPartId=-1|Location.X=1101|Location.Y=638|Color=8388608|FontID=8|Text=0.1UF|Name=VALUE
|RECORD=2|OwnerIndex=80|OwnerPartId=1|FormalType=1|Electrical=4|PinConglomerate=32|PinLength=10|Location.X=1100|Location.Y=650|Name=2|Designator=2|SwapIdPin=2|SwapIDPart=1|PinPropagationDelay=0.000000E+000
|RECORD=2|OwnerIndex=80|OwnerPartId=1|FormalType=1|Electrical=4|PinConglomerate=34|PinLength=10|Location.X=1090|Location.Y=650|Name=1|Designator=1|SwapIdPin=1|SwapIDPart=1|PinPropagationDelay=0.000000E+000
|RECORD=13|OwnerIndex=80|IsNotAccesible=T|IndexInSheet=20|OwnerPartId=1|Location.X=1097|Location.X_Frac=50000|Location.Y=650|Corner.X=1100|Corner.Y=650|LineWidth=1|Color=16711680
|RECORD=13|OwnerIndex=80|IsNotAccesible=T|IndexInSheet=21|OwnerPartId=1|Location.X=1090|Location.Y=650|Corner.X=1092|Corner.X_Frac=50000|Corner.Y=650|LineWidth=1|Color=16711680
|RECORD=13|OwnerIndex=80|IsNotAccesible=T|IndexInSheet=22|OwnerPartId=1|Location.X=1097|Location.X_Frac=50000|Location.Y=655|Corner.X=1097|Corner.X_Frac=50000|Corner.Y=645|LineWidth=1|Color=16711680
|RECORD=13|OwnerIndex=80|IsNotAccesible=T|IndexInSheet=23|OwnerPartId=1|Location.X=1092|Location.X_Frac=50000|Location.Y=655|Corner.X=1092|Corner.X_Frac=50000|Corner.Y=645|LineWidth=1|Color=16711680
|RECORD=41|OwnerIndex=80|IndexInSheet=24|OwnerPartId=-1|Location.X=1078|Location.Y=656|Color=8388608|FontID=1|IsHidden=T|Text=<VALENTIUM>|Name=VALENTIUM PART NUM
|RECORD=34|OwnerIndex=80|IndexInSheet=-1|OwnerPartId=-1|Location.X=1070|Location.Y=636|Color=8388608|FontID=1|Text=C53|Name=Designator|ReadOnlyState=1
|RECORD=41|OwnerIndex=80|IndexInSheet=-1|OwnerPartId=-1|Location.X=1078|Location.Y=656|Color=8388608|FontID=1|IsHidden=T|Text=CAP_0402_0.1UF_50V|Name=Comment|ReadOnlyState=1
|RECORD=44|OwnerIndex=80
|RECORD=45|OwnerIndex=110|IndexInSheet=-1|Description=Chip Capacitor, 0402, 2-Leads, Body 1.00x0.50mm, IPC Medium Density|UseComponentLibrary=T|ModelName=CAPC1005X06N|ModelType=PCBLIB|DatafileCount=1|ModelDatafileEntity0=CAPC1005X06N|ModelDatafileKind0=PCBLib|IsCurrent=T|DatalinksLocked=T|DatabaseDatalinksLocked=T|IntegratedModel=T|DatabaseModel=T
|RECORD=46|OwnerIndex=111
|RECORD=48|OwnerIndex=111
|RECORD=1|LibReference=CAP_0402_0.1UF_50V|ComponentDescription=CAP, CER, 0.1UF, 50V, 10%, X7R, AEC-Q200, 0402|PartCount=2|DisplayModeCount=1|IndexInSheet=35|OwnerPartId=-1|Location.X=1090|Location.Y=640|Orientation=1|CurrentPartId=1|LibraryPath=*|SourceLibraryName=Capacitors.IntLib|TargetFileName=*|AreaColor=11599871|Color=128|PartIDLocked=F|DesignItemId=CAP_0402_0.1UF_50V|AllPinCount=2
|RECORD=41|OwnerIndex=114|OwnerPartId=-1|Location.X=1038|Location.Y=666|Color=8388608|FontID=8|IsHidden=T|Text=CAP, CER|Name=CATEGORY
|RECORD=41|OwnerIndex=114|IndexInSheet=1|OwnerPartId=-1|Location.X=1038|Location.Y=666|Color=8388608|FontID=8|IsHidden=T|Text=TDK|Name=MFG NAME
|RECORD=41|OwnerIndex=114|IndexInSheet=2|OwnerPartId=-1|Location.X=1038|Location.Y=666|Color=8388608|FontID=8|IsHidden=T|Text=CGA2B3X7R1H104K050BB|Name=MFG PART NUM
|RECORD=41|OwnerIndex=114|IndexInSheet=3|OwnerPartId=-1|Location.X=1038|Location.Y=666|Color=8388608|FontID=8|IsHidden=T|Text=10/23/2013|Name=MODIFY DATE
|RECORD=41|OwnerIndex=114|IndexInSheet=4|OwnerPartId=-1|Location.X=1038|Location.Y=666|Color=8388608|FontID=8|IsHidden=T|Name=Date
|RECORD=41|OwnerIndex=114|IndexInSheet=5|OwnerPartId=-1|Location.X=1038|Location.Y=666|Color=8388608|FontID=8|IsHidden=T|Text=*|Name=SHEETPART
|RECORD=41|OwnerIndex=114|IndexInSheet=6|OwnerPartId=-1|Location.X=1038|Location.Y=666|Color=8388608|FontID=8|IsHidden=T|Text=10%|Name=P1
|RECORD=41|OwnerIndex=114|IndexInSheet=7|OwnerPartId=-1|Location.X=1038|Location.Y=666|Color=8388608|FontID=8|IsHidden=T|Text=125C|Name=MAXTEMP
|RECORD=41|OwnerIndex=114|IndexInSheet=8|OwnerPartId=-1|Location.X=1038|Location.Y=666|Color=8388608|FontID=8|IsHidden=T|Text=-55C|Name=MINTEMP
|RECORD=41|OwnerIndex=114|IndexInSheet=9|OwnerPartId=-1|Location.X=1038|Location.Y=666|Color=8388608|FontID=8|IsHidden=T|Text=AEC-Q200|Name=OTHER
|RECORD=41|OwnerIndex=114|IndexInSheet=10|OwnerPartId=-1|Location.X=1038|Location.Y=666|Color=8388608|FontID=8|IsHidden=T|Text=50V|Name=P2
|RECORD=41|OwnerIndex=114|IndexInSheet=11|OwnerPartId=-1|Location.X=1038|Location.Y=666|Color=8388608|FontID=8|IsHidden=T|Text=X7R|Name=P3
|RECORD=41|OwnerIndex=114|IndexInSheet=12|OwnerPartId=-1|Location.X=1038|Location.Y=666|Color=8388608|FontID=8|IsHidden=T|Text=0402|Name=Size
|RECORD=41|OwnerIndex=114|IndexInSheet=13|OwnerPartId=-1|Location.X=1038|Location.Y=666|Color=8388608|FontID=8|IsHidden=T|Name=SUB
|RECORD=41|OwnerIndex=114|IndexInSheet=14|OwnerPartId=-1|Location.X=1038|Location.Y=666|Color=8388608|FontID=1|IsHidden=T|Text=CAP, CER, 0.1UF, 50V, 10%, X7R, AEC-Q200, 0402|Name=DESC
|RECORD=41|OwnerIndex=114|IndexInSheet=15|OwnerPartId=-1|Location.X=1038|Location.Y=666|Color=8388608|FontID=1|IsHidden=T|Text=Digi-Key|Name=Supplier 1|ReadOnlyState=3
|RECORD=41|OwnerIndex=114|IndexInSheet=16|OwnerPartId=-1|Location.X=1038|Location.Y=666|Color=8388608|FontID=1|IsHidden=T|Text=445-6899-1-ND|Name=Supplier Part Number 1|ReadOnlyState=3
|RECORD=41|OwnerIndex=114|IndexInSheet=17|OwnerPartId=-1|Location.X=1060|Location.Y=660|Color=8388608|FontID=8|Text=0.1UF|Name=VALUE
|RECORD=2|OwnerIndex=114|OwnerPartId=1|FormalType=1|Electrical=4|PinConglomerate=32|PinLength=10|Location.X=1060|Location.Y=660|Name=2|Designator=2|SwapIdPin=2|SwapIDPart=1|PinPropagationDelay=0.000000E+000
|RECORD=2|OwnerIndex=114|OwnerPartId=1|FormalType=1|Electrical=4|PinConglomerate=34|PinLength=10|Location.X=1050|Location.Y=660|Name=1|Designator=1|SwapIdPin=1|SwapIDPart=1|PinPropagationDelay=0.000000E+000
|RECORD=13|OwnerIndex=114|IsNotAccesible=T|IndexInSheet=20|OwnerPartId=1|Location.X=1057|Location.X_Frac=50000|Location.Y=660|Corner.X=1060|Corner.Y=660|LineWidth=1|Color=16711680
|RECORD=13|OwnerIndex=114|IsNotAccesible=T|IndexInSheet=21|OwnerPartId=1|Location.X=1050|Location.Y=660|Corner.X=1052|Corner.X_Frac=50000|Corner.Y=660|LineWidth=1|Color=16711680
|RECORD=13|OwnerIndex=114|IsNotAccesible=T|IndexInSheet=22|OwnerPartId=1|Location.X=1057|Location.X_Frac=50000|Location.Y=665|Corner.X=1057|Corner.X_Frac=50000|Corner.Y=655|LineWidth=1|Color=16711680
|RECORD=13|OwnerIndex=114|IsNotAccesible=T|IndexInSheet=23|OwnerPartId=1|Location.X=1052|Location.X_Frac=50000|Location.Y=665|Corner.X=1052|Corner.X_Frac=50000|Corner.Y=655|LineWidth=1|Color=16711680
|RECORD=41|OwnerIndex=114|IndexInSheet=24|OwnerPartId=-1|Location.X=1038|Location.Y=666|Color=8388608|FontID=1|IsHidden=T|Text=<VALENTIUM>|Name=VALENTIUM PART NUM
|RECORD=34|OwnerIndex=114|IndexInSheet=-1|OwnerPartId=-1|Location.X=1030|Location.Y=660|Color=8388608|FontID=1|Text=C52|Name=Designator|ReadOnlyState=1
|RECORD=41|OwnerIndex=114|IndexInSheet=-1|OwnerPartId=-1|Location.X=1038|Location.Y=666|Color=8388608|FontID=1|IsHidden=T|Text=CAP_0402_0.1UF_50V|Name=Comment|ReadOnlyState=1
|RECORD=44|OwnerIndex=114
|RECORD=45|OwnerIndex=144|IndexInSheet=-1|Description=Chip Capacitor, 0402, 2-Leads, Body 1.00x0.50mm, IPC Medium Density|UseComponentLibrary=T|ModelName=CAPC1005X06N|ModelType=PCBLIB|DatafileCount=1|ModelDatafileEntity0=CAPC1005X06N|ModelDatafileKind0=PCBLib|IsCurrent=T|DatalinksLocked=T|DatabaseDatalinksLocked=T|IntegratedModel=T|DatabaseModel=T
|RECORD=46|OwnerIndex=145
|RECORD=48|OwnerIndex=145
|RECORD=1|LibReference=RES_0402_0|ComponentDescription=RES, 0. OHM, 1%, 1/16W, TF, AEC-Q200, 0402|PartCount=2|DisplayModeCount=1|IndexInSheet=36|OwnerPartId=-1|Location.X=670|Location.Y=640|CurrentPartId=1|LibraryPath=*|SourceLibraryName=Resistors.IntLib|TargetFileName=*|AreaColor=11599871|Color=128|PartIDLocked=F|DesignItemId=RES_0402_0|AllPinCount=2
|RECORD=41|OwnerIndex=148|OwnerPartId=-1|Location.X=670|Location.Y=640|Color=8388608|FontID=8|IsHidden=T|Text=7/25/2013|Name=ModifyDate
|RECORD=41|OwnerIndex=148|IndexInSheet=1|OwnerPartId=-1|Location.X=670|Location.Y=640|Color=8388608|FontID=8|IsHidden=T|Text=ERJ-2GE0R00X|Name=MFG PART NUM
|RECORD=41|OwnerIndex=148|IndexInSheet=2|OwnerPartId=-1|Location.X=670|Location.Y=640|Color=8388608|FontID=8|IsHidden=T|Text=PANASONIC|Name=MFG NAME
|RECORD=41|OwnerIndex=148|IndexInSheet=3|OwnerPartId=-1|Location.X=670|Location.Y=640|Color=8388608|FontID=8|IsHidden=T|Text=RES|Name=CATEGORY
|RECORD=41|OwnerIndex=148|IndexInSheet=4|OwnerPartId=-1|Location.X=668|Location.Y=650|Color=8388608|FontID=8|IsHidden=T|Text=7/26/2013|Name=Date
|RECORD=41|OwnerIndex=148|IndexInSheet=5|OwnerPartId=-1|Location.X=660|Location.X_Frac=55769|Location.Y=650|Color=8388608|FontID=8|IsHidden=T|Text=1%|Name=P1
|RECORD=41|OwnerIndex=148|IndexInSheet=6|OwnerPartId=-1|Location.X=660|Location.X_Frac=55769|Location.Y=650|Color=8388608|FontID=8|IsHidden=T|Text=TF|Name=P3
|RECORD=41|OwnerIndex=148|IndexInSheet=7|OwnerPartId=-1|Location.X=660|Location.X_Frac=55769|Location.Y=650|Color=8388608|FontID=8|IsHidden=T|Text=1/16W|Name=P2
|RECORD=41|OwnerIndex=148|IndexInSheet=8|OwnerPartId=-1|Location.X=660|Location.X_Frac=55769|Location.Y=650|Color=8388608|FontID=8|IsHidden=T|Text=155C|Name=MAXTEMP
|RECORD=41|OwnerIndex=148|IndexInSheet=9|OwnerPartId=-1|Location.X=660|Location.X_Frac=55769|Location.Y=650|Color=8388608|FontID=8|IsHidden=T|Text=-55C|Name=MINTEMP
|RECORD=41|OwnerIndex=148|IndexInSheet=10|OwnerPartId=-1|Location.X=660|Location.X_Frac=55769|Location.Y=650|Color=8388608|FontID=8|IsHidden=T|Text=100PPM, AEC-Q200|Name=OTHER
|RECORD=41|OwnerIndex=148|IndexInSheet=11|OwnerPartId=-1|Location.X=660|Location.X_Frac=55769|Location.Y=650|Color=8388608|FontID=8|IsHidden=T|Text=0402|Name=SIZE
|RECORD=41|OwnerIndex=148|IndexInSheet=12|OwnerPartId=-1|Location.X=660|Location.X_Frac=55769|Location.Y=650|Color=8388608|FontID=8|IsHidden=T|Text=GENERIC|Name=SUB
|RECORD=41|OwnerIndex=148|IndexInSheet=13|OwnerPartId=-1|Location.X=655|Location.X_Frac=98077|Location.Y=626|Color=8388608|FontID=1|IsHidden=T|Text=*|Name=SHEETPART
|RECORD=41|OwnerIndex=148|IndexInSheet=14|OwnerPartId=-1|Location.X=655|Location.X_Frac=98077|Location.Y=654|Color=8388608|FontID=1|IsHidden=T|Text=RES, 0 OHM, 1%, 1/16W, TF, AEC-Q200, 0402|Name=DESC
|RECORD=41|OwnerIndex=148|IndexInSheet=15|OwnerPartId=-1|Location.X=656|Location.X_Frac=60577|Location.Y=654|Color=8388608|FontID=1|IsHidden=T|Text=Digi-Key|Name=Supplier 1|ReadOnlyState=3
|RECORD=41|OwnerIndex=148|IndexInSheet=16|OwnerPartId=-1|Location.X=656|Location.X_Frac=60577|Location.Y=654|Color=8388608|FontID=1|IsHidden=T|Text=P0.0JCT-ND|Name=Supplier Part Number 1|ReadOnlyState=3
|RECORD=41|OwnerIndex=148|IndexInSheet=17|OwnerPartId=-1|Location.X=656|Location.X_Frac=61102|Location.Y=654|Color=8388608|FontID=1|IsHidden=T|Text=<VELENTIUM>|Name=VELENTIUM PART NUM
|RECORD=41|OwnerIndex=148|IndexInSheet=18|OwnerPartId=-1|Location.X=679|Location.Y=624|Color=8388608|FontID=8|Text=0 OHM|Name=VALUE
|RECORD=2|OwnerIndex=148|OwnerPartId=1|FormalType=1|Electrical=4|PinConglomerate=34|PinLength=10|Location.X=680|Location.Y=640|Name=1|Designator=1|PinPropagationDelay=0.000000E+000
|RECORD=2|OwnerIndex=148|OwnerPartId=1|FormalType=1|Electrical=4|PinConglomerate=32|PinLength=10|Location.X=710|Location.Y=640|Name=2|Designator=2|PinPropagationDelay=0.000000E+000
|RECORD=6|OwnerIndex=148|IsNotAccesible=T|IndexInSheet=21|OwnerPartId=1|LineWidth=1|Color=16711680|LocationCount=7|X1=710|Y1=640|X2=707|Y2=643|X3=701|Y3=637|X4=695|Y4=643|X5=689|Y5=637|X6=683|Y6=643|X7=680|Y7=640
|RECORD=34|OwnerIndex=148|IndexInSheet=-1|OwnerPartId=-1|Location.X=679|Location.Y=644|Color=8388608|FontID=1|Text=R24|Name=Designator|ReadOnlyState=1
|RECORD=41|OwnerIndex=148|IndexInSheet=-1|OwnerPartId=-1|Location.X=690|Location.Y=630|Color=8388608|FontID=1|IsHidden=T|Text=="MFG PART NUM"|Name=Comment
|RECORD=44|OwnerIndex=148
|RECORD=45|OwnerIndex=175|IndexInSheet=-1|Description=Chip Resistor, 0402, 2-Leads, Body 1.00x0.50mm, IPC Medium Density|UseComponentLibrary=T|ModelName=RESC1005X04N|ModelType=PCBLIB|DatafileCount=1|ModelDatafileEntity0=RESC1005X04N|ModelDatafileKind0=PCBLib|IsCurrent=T|DatalinksLocked=T|DatabaseDatalinksLocked=T|IntegratedModel=T|DatabaseModel=T
|RECORD=46|OwnerIndex=176
|RECORD=48|OwnerIndex=176
|RECORD=1|LibReference=RES_0402_0|ComponentDescription=RES, 0. OHM, 1%, 1/16W, TF, AEC-Q200, 0402|PartCount=2|DisplayModeCount=1|IndexInSheet=37|OwnerPartId=-1|Location.X=670|Location.Y=780|CurrentPartId=1|LibraryPath=*|SourceLibraryName=Resistors.IntLib|TargetFileName=*|AreaColor=11599871|Color=128|PartIDLocked=F|DesignItemId=RES_0402_0|AllPinCount=2
|RECORD=41|OwnerIndex=179|OwnerPartId=-1|Location.X=670|Location.Y=780|Color=8388608|FontID=8|IsHidden=T|Text=7/25/2013|Name=ModifyDate
|RECORD=41|OwnerIndex=179|IndexInSheet=1|OwnerPartId=-1|Location.X=670|Location.Y=780|Color=8388608|FontID=8|IsHidden=T|Text=ERJ-2GE0R00X|Name=MFG PART NUM
|RECORD=41|OwnerIndex=179|IndexInSheet=2|OwnerPartId=-1|Location.X=670|Location.Y=780|Color=8388608|FontID=8|IsHidden=T|Text=PANASONIC|Name=MFG NAME
|RECORD=41|OwnerIndex=179|IndexInSheet=3|OwnerPartId=-1|Location.X=670|Location.Y=780|Color=8388608|FontID=8|IsHidden=T|Text=RES|Name=CATEGORY
|RECORD=41|OwnerIndex=179|IndexInSheet=4|OwnerPartId=-1|Location.X=668|Location.Y=790|Color=8388608|FontID=8|IsHidden=T|Text=7/26/2013|Name=Date
|RECORD=41|OwnerIndex=179|IndexInSheet=5|OwnerPartId=-1|Location.X=660|Location.X_Frac=55769|Location.Y=790|Color=8388608|FontID=8|IsHidden=T|Text=1%|Name=P1
|RECORD=41|OwnerIndex=179|IndexInSheet=6|OwnerPartId=-1|Location.X=660|Location.X_Frac=55769|Location.Y=790|Color=8388608|FontID=8|IsHidden=T|Text=TF|Name=P3
|RECORD=41|OwnerIndex=179|IndexInSheet=7|OwnerPartId=-1|Location.X=660|Location.X_Frac=55769|Location.Y=790|Color=8388608|FontID=8|IsHidden=T|Text=1/16W|Name=P2
|RECORD=41|OwnerIndex=179|IndexInSheet=8|OwnerPartId=-1|Location.X=660|Location.X_Frac=55769|Location.Y=790|Color=8388608|FontID=8|IsHidden=T|Text=155C|Name=MAXTEMP
|RECORD=41|OwnerIndex=179|IndexInSheet=9|OwnerPartId=-1|Location.X=660|Location.X_Frac=55769|Location.Y=790|Color=8388608|FontID=8|IsHidden=T|Text=-55C|Name=MINTEMP
|RECORD=41|OwnerIndex=179|IndexInSheet=10|OwnerPartId=-1|Location.X=660|Location.X_Frac=55769|Location.Y=790|Color=8388608|FontID=8|IsHidden=T|Text=100PPM, AEC-Q200|Name=OTHER
|RECORD=41|OwnerIndex=179|IndexInSheet=11|OwnerPartId=-1|Location.X=660|Location.X_Frac=55769|Location.Y=790|Color=8388608|FontID=8|IsHidden=T|Text=0402|Name=SIZE
|RECORD=41|OwnerIndex=179|IndexInSheet=12|OwnerPartId=-1|Location.X=660|Location.X_Frac=55769|Location.Y=790|Color=8388608|FontID=8|IsHidden=T|Text=GENERIC|Name=SUB
|RECORD=41|OwnerIndex=179|IndexInSheet=13|OwnerPartId=-1|Location.X=655|Location.X_Frac=98077|Location.Y=766|Color=8388608|FontID=1|IsHidden=T|Text=*|Name=SHEETPART
|RECORD=41|OwnerIndex=179|IndexInSheet=14|OwnerPartId=-1|Location.X=655|Location.X_Frac=98077|Location.Y=794|Color=8388608|FontID=1|IsHidden=T|Text=RES, 0 OHM, 1%, 1/16W, TF, AEC-Q200, 0402|Name=DESC
|RECORD=41|OwnerIndex=179|IndexInSheet=15|OwnerPartId=-1|Location.X=656|Location.X_Frac=60577|Location.Y=794|Color=8388608|FontID=1|IsHidden=T|Text=Digi-Key|Name=Supplier 1|ReadOnlyState=3
|RECORD=41|OwnerIndex=179|IndexInSheet=16|OwnerPartId=-1|Location.X=656|Location.X_Frac=60577|Location.Y=794|Color=8388608|FontID=1|IsHidden=T|Text=P0.0JCT-ND|Name=Supplier Part Number 1|ReadOnlyState=3
|RECORD=41|OwnerIndex=179|IndexInSheet=17|OwnerPartId=-1|Location.X=656|Location.X_Frac=61102|Location.Y=794|Color=8388608|FontID=1|IsHidden=T|Text=<VELENTIUM>|Name=VELENTIUM PART NUM
|RECORD=41|OwnerIndex=179|IndexInSheet=18|OwnerPartId=-1|Location.X=679|Location.Y=764|Color=8388608|FontID=8|Text=0 OHM|Name=VALUE
|RECORD=2|OwnerIndex=179|OwnerPartId=1|FormalType=1|Electrical=4|PinConglomerate=34|PinLength=10|Location.X=680|Location.Y=780|Name=1|Designator=1|PinPropagationDelay=0.000000E+000
|RECORD=2|OwnerIndex=179|OwnerPartId=1|FormalType=1|Electrical=4|PinConglomerate=32|PinLength=10|Location.X=710|Location.Y=780|Name=2|Designator=2|PinPropagationDelay=0.000000E+000
|RECORD=6|OwnerIndex=179|IsNotAccesible=T|IndexInSheet=21|OwnerPartId=1|LineWidth=1|Color=16711680|LocationCount=7|X1=710|Y1=780|X2=707|Y2=783|X3=701|Y3=777|X4=695|Y4=783|X5=689|Y5=777|X6=683|Y6=783|X7=680|Y7=780
|RECORD=34|OwnerIndex=179|IndexInSheet=-1|OwnerPartId=-1|Location.X=679|Location.Y=784|Color=8388608|FontID=1|Text=R23|Name=Designator|ReadOnlyState=1
|RECORD=41|OwnerIndex=179|IndexInSheet=-1|OwnerPartId=-1|Location.X=690|Location.Y=770|Color=8388608|FontID=1|IsHidden=T|Text=="MFG PART NUM"|Name=Comment
|RECORD=44|OwnerIndex=179
|RECORD=45|OwnerIndex=206|IndexInSheet=-1|Description=Chip Resistor, 0402, 2-Leads, Body 1.00x0.50mm, IPC Medium Density|UseComponentLibrary=T|ModelName=RESC1005X04N|ModelType=PCBLIB|DatafileCount=1|ModelDatafileEntity0=RESC1005X04N|ModelDatafileKind0=PCBLib|IsCurrent=T|DatalinksLocked=T|DatabaseDatalinksLocked=T|IntegratedModel=T|DatabaseModel=T
|RECORD=46|OwnerIndex=207
|RECORD=48|OwnerIndex=207
|RECORD=1|LibReference=CAP_0402_0.1UF_50V|ComponentDescription=CAP, CER, 0.1UF, 50V, 10%, X7R, AEC-Q200, 0402|PartCount=2|DisplayModeCount=1|IndexInSheet=38|OwnerPartId=-1|Location.X=1130|Location.Y=670|Orientation=1|CurrentPartId=1|LibraryPath=*|SourceLibraryName=Capacitors.IntLib|TargetFileName=*|AreaColor=11599871|Color=128|PartIDLocked=F|DesignItemId=CAP_0402_0.1UF_50V|AllPinCount=2
|RECORD=41|OwnerIndex=210|OwnerPartId=-1|Location.X=1078|Location.Y=696|Color=8388608|FontID=8|IsHidden=T|Text=CAP, CER|Name=CATEGORY
|RECORD=41|OwnerIndex=210|IndexInSheet=1|OwnerPartId=-1|Location.X=1078|Location.Y=696|Color=8388608|FontID=8|IsHidden=T|Text=TDK|Name=MFG NAME
|RECORD=41|OwnerIndex=210|IndexInSheet=2|OwnerPartId=-1|Location.X=1078|Location.Y=696|Color=8388608|FontID=8|IsHidden=T|Text=CGA2B3X7R1H104K050BB|Name=MFG PART NUM
|RECORD=41|OwnerIndex=210|IndexInSheet=3|OwnerPartId=-1|Location.X=1078|Location.Y=696|Color=8388608|FontID=8|IsHidden=T|Text=10/23/2013|Name=MODIFY DATE
|RECORD=41|OwnerIndex=210|IndexInSheet=4|OwnerPartId=-1|Location.X=1078|Location.Y=696|Color=8388608|FontID=8|IsHidden=T|Name=Date
|RECORD=41|OwnerIndex=210|IndexInSheet=5|OwnerPartId=-1|Location.X=1078|Location.Y=696|Color=8388608|FontID=8|IsHidden=T|Text=*|Name=SHEETPART
|RECORD=41|OwnerIndex=210|IndexInSheet=6|OwnerPartId=-1|Location.X=1078|Location.Y=696|Color=8388608|FontID=8|IsHidden=T|Text=10%|Name=P1
|RECORD=41|OwnerIndex=210|IndexInSheet=7|OwnerPartId=-1|Location.X=1078|Location.Y=696|Color=8388608|FontID=8|IsHidden=T|Text=125C|Name=MAXTEMP
|RECORD=41|OwnerIndex=210|IndexInSheet=8|OwnerPartId=-1|Location.X=1078|Location.Y=696|Color=8388608|FontID=8|IsHidden=T|Text=-55C|Name=MINTEMP
|RECORD=41|OwnerIndex=210|IndexInSheet=9|OwnerPartId=-1|Location.X=1078|Location.Y=696|Color=8388608|FontID=8|IsHidden=T|Text=AEC-Q200|Name=OTHER
|RECORD=41|OwnerIndex=210|IndexInSheet=10|OwnerPartId=-1|Location.X=1078|Location.Y=696|Color=8388608|FontID=8|IsHidden=T|Text=50V|Name=P2
|RECORD=41|OwnerIndex=210|IndexInSheet=11|OwnerPartId=-1|Location.X=1078|Location.Y=696|Color=8388608|FontID=8|IsHidden=T|Text=X7R|Name=P3
|RECORD=41|OwnerIndex=210|IndexInSheet=12|OwnerPartId=-1|Location.X=1078|Location.Y=696|Color=8388608|FontID=8|IsHidden=T|Text=0402|Name=Size
|RECORD=41|OwnerIndex=210|IndexInSheet=13|OwnerPartId=-1|Location.X=1078|Location.Y=696|Color=8388608|FontID=8|IsHidden=T|Name=SUB
|RECORD=41|OwnerIndex=210|IndexInSheet=14|OwnerPartId=-1|Location.X=1078|Location.Y=696|Color=8388608|FontID=1|IsHidden=T|Text=CAP, CER, 0.1UF, 50V, 10%, X7R, AEC-Q200, 0402|Name=DESC
|RECORD=41|OwnerIndex=210|IndexInSheet=15|OwnerPartId=-1|Location.X=1078|Location.Y=696|Color=8388608|FontID=1|IsHidden=T|Text=Digi-Key|Name=Supplier 1|ReadOnlyState=3
|RECORD=41|OwnerIndex=210|IndexInSheet=16|OwnerPartId=-1|Location.X=1078|Location.Y=696|Color=8388608|FontID=1|IsHidden=T|Text=445-6899-1-ND|Name=Supplier Part Number 1|ReadOnlyState=3
|RECORD=41|OwnerIndex=210|IndexInSheet=17|OwnerPartId=-1|Location.X=1101|Location.Y=678|Color=8388608|FontID=8|Text=0.1UF|Name=VALUE
|RECORD=2|OwnerIndex=210|OwnerPartId=1|FormalType=1|Electrical=4|PinConglomerate=32|PinLength=10|Location.X=1100|Location.Y=690|Name=2|Designator=2|SwapIdPin=2|SwapIDPart=1|PinPropagationDelay=0.000000E+000
|RECORD=2|OwnerIndex=210|OwnerPartId=1|FormalType=1|Electrical=4|PinConglomerate=34|PinLength=10|Location.X=1090|Location.Y=690|Name=1|Designator=1|SwapIdPin=1|SwapIDPart=1|PinPropagationDelay=0.000000E+000
|RECORD=13|OwnerIndex=210|IsNotAccesible=T|IndexInSheet=20|OwnerPartId=1|Location.X=1097|Location.X_Frac=50000|Location.Y=690|Corner.X=1100|Corner.Y=690|LineWidth=1|Color=16711680
|RECORD=13|OwnerIndex=210|IsNotAccesible=T|IndexInSheet=21|OwnerPartId=1|Location.X=1090|Location.Y=690|Corner.X=1092|Corner.X_Frac=50000|Corner.Y=690|LineWidth=1|Color=16711680
|RECORD=13|OwnerIndex=210|IsNotAccesible=T|IndexInSheet=22|OwnerPartId=1|Location.X=1097|Location.X_Frac=50000|Location.Y=695|Corner.X=1097|Corner.X_Frac=50000|Corner.Y=685|LineWidth=1|Color=16711680
|RECORD=13|OwnerIndex=210|IsNotAccesible=T|IndexInSheet=23|OwnerPartId=1|Location.X=1092|Location.X_Frac=50000|Location.Y=695|Corner.X=1092|Corner.X_Frac=50000|Corner.Y=685|LineWidth=1|Color=16711680
|RECORD=41|OwnerIndex=210|IndexInSheet=24|OwnerPartId=-1|Location.X=1078|Location.Y=696|Color=8388608|FontID=1|IsHidden=T|Text=<VALENTIUM>|Name=VALENTIUM PART NUM
|RECORD=34|OwnerIndex=210|IndexInSheet=-1|OwnerPartId=-1|Location.X=1070|Location.Y=676|Color=8388608|FontID=1|Text=C51|Name=Designator|ReadOnlyState=1
|RECORD=41|OwnerIndex=210|IndexInSheet=-1|OwnerPartId=-1|Location.X=1078|Location.Y=696|Color=8388608|FontID=1|IsHidden=T|Text=CAP_0402_0.1UF_50V|Name=Comment|ReadOnlyState=1
|RECORD=44|OwnerIndex=210
|RECORD=45|OwnerIndex=240|IndexInSheet=-1|Description=Chip Capacitor, 0402, 2-Leads, Body 1.00x0.50mm, IPC Medium Density|UseComponentLibrary=T|ModelName=CAPC1005X06N|ModelType=PCBLIB|DatafileCount=1|ModelDatafileEntity0=CAPC1005X06N|ModelDatafileKind0=PCBLib|IsCurrent=T|DatalinksLocked=T|DatabaseDatalinksLocked=T|IntegratedModel=T|DatabaseModel=T
|RECORD=46|OwnerIndex=241
|RECORD=48|OwnerIndex=241
|RECORD=1|LibReference=CAP_0402_0.1UF_50V|ComponentDescription=CAP, CER, 0.1UF, 50V, 10%, X7R, AEC-Q200, 0402|PartCount=2|DisplayModeCount=1|IndexInSheet=39|OwnerPartId=-1|Location.X=1130|Location.Y=710|Orientation=1|CurrentPartId=1|LibraryPath=*|SourceLibraryName=Capacitors.IntLib|TargetFileName=*|AreaColor=11599871|Color=128|PartIDLocked=F|DesignItemId=CAP_0402_0.1UF_50V|AllPinCount=2
|RECORD=41|OwnerIndex=244|OwnerPartId=-1|Location.X=1078|Location.Y=736|Color=8388608|FontID=8|IsHidden=T|Text=CAP, CER|Name=CATEGORY
|RECORD=41|OwnerIndex=244|IndexInSheet=1|OwnerPartId=-1|Location.X=1078|Location.Y=736|Color=8388608|FontID=8|IsHidden=T|Text=TDK|Name=MFG NAME
|RECORD=41|OwnerIndex=244|IndexInSheet=2|OwnerPartId=-1|Location.X=1078|Location.Y=736|Color=8388608|FontID=8|IsHidden=T|Text=CGA2B3X7R1H104K050BB|Name=MFG PART NUM
|RECORD=41|OwnerIndex=244|IndexInSheet=3|OwnerPartId=-1|Location.X=1078|Location.Y=736|Color=8388608|FontID=8|IsHidden=T|Text=10/23/2013|Name=MODIFY DATE
|RECORD=41|OwnerIndex=244|IndexInSheet=4|OwnerPartId=-1|Location.X=1078|Location.Y=736|Color=8388608|FontID=8|IsHidden=T|Name=Date
|RECORD=41|OwnerIndex=244|IndexInSheet=5|OwnerPartId=-1|Location.X=1078|Location.Y=736|Color=8388608|FontID=8|IsHidden=T|Text=*|Name=SHEETPART
|RECORD=41|OwnerIndex=244|IndexInSheet=6|OwnerPartId=-1|Location.X=1078|Location.Y=736|Color=8388608|FontID=8|IsHidden=T|Text=10%|Name=P1
|RECORD=41|OwnerIndex=244|IndexInSheet=7|OwnerPartId=-1|Location.X=1078|Location.Y=736|Color=8388608|FontID=8|IsHidden=T|Text=125C|Name=MAXTEMP
|RECORD=41|OwnerIndex=244|IndexInSheet=8|OwnerPartId=-1|Location.X=1078|Location.Y=736|Color=8388608|FontID=8|IsHidden=T|Text=-55C|Name=MINTEMP
|RECORD=41|OwnerIndex=244|IndexInSheet=9|OwnerPartId=-1|Location.X=1078|Location.Y=736|Color=8388608|FontID=8|IsHidden=T|Text=AEC-Q200|Name=OTHER
|RECORD=41|OwnerIndex=244|IndexInSheet=10|OwnerPartId=-1|Location.X=1078|Location.Y=736|Color=8388608|FontID=8|IsHidden=T|Text=50V|Name=P2
|RECORD=41|OwnerIndex=244|IndexInSheet=11|OwnerPartId=-1|Location.X=1078|Location.Y=736|Color=8388608|FontID=8|IsHidden=T|Text=X7R|Name=P3
|RECORD=41|OwnerIndex=244|IndexInSheet=12|OwnerPartId=-1|Location.X=1078|Location.Y=736|Color=8388608|FontID=8|IsHidden=T|Text=0402|Name=Size
|RECORD=41|OwnerIndex=244|IndexInSheet=13|OwnerPartId=-1|Location.X=1078|Location.Y=736|Color=8388608|FontID=8|IsHidden=T|Name=SUB
|RECORD=41|OwnerIndex=244|IndexInSheet=14|OwnerPartId=-1|Location.X=1078|Location.Y=736|Color=8388608|FontID=1|IsHidden=T|Text=CAP, CER, 0.1UF, 50V, 10%, X7R, AEC-Q200, 0402|Name=DESC
|RECORD=41|OwnerIndex=244|IndexInSheet=15|OwnerPartId=-1|Location.X=1078|Location.Y=736|Color=8388608|FontID=1|IsHidden=T|Text=Digi-Key|Name=Supplier 1|ReadOnlyState=3
|RECORD=41|OwnerIndex=244|IndexInSheet=16|OwnerPartId=-1|Location.X=1078|Location.Y=736|Color=8388608|FontID=1|IsHidden=T|Text=445-6899-1-ND|Name=Supplier Part Number 1|ReadOnlyState=3
|RECORD=41|OwnerIndex=244|IndexInSheet=17|OwnerPartId=-1|Location.X=1101|Location.Y=718|Color=8388608|FontID=8|Text=0.1UF|Name=VALUE
|RECORD=2|OwnerIndex=244|OwnerPartId=1|FormalType=1|Electrical=4|PinConglomerate=32|PinLength=10|Location.X=1100|Location.Y=730|Name=2|Designator=2|SwapIdPin=2|SwapIDPart=1|PinPropagationDelay=0.000000E+000
|RECORD=2|OwnerIndex=244|OwnerPartId=1|FormalType=1|Electrical=4|PinConglomerate=34|PinLength=10|Location.X=1090|Location.Y=730|Name=1|Designator=1|SwapIdPin=1|SwapIDPart=1|PinPropagationDelay=0.000000E+000
|RECORD=13|OwnerIndex=244|IsNotAccesible=T|IndexInSheet=20|OwnerPartId=1|Location.X=1097|Location.X_Frac=50000|Location.Y=730|Corner.X=1100|Corner.Y=730|LineWidth=1|Color=16711680
|RECORD=13|OwnerIndex=244|IsNotAccesible=T|IndexInSheet=21|OwnerPartId=1|Location.X=1090|Location.Y=730|Corner.X=1092|Corner.X_Frac=50000|Corner.Y=730|LineWidth=1|Color=16711680
|RECORD=13|OwnerIndex=244|IsNotAccesible=T|IndexInSheet=22|OwnerPartId=1|Location.X=1097|Location.X_Frac=50000|Location.Y=735|Corner.X=1097|Corner.X_Frac=50000|Corner.Y=725|LineWidth=1|Color=16711680
|RECORD=13|OwnerIndex=244|IsNotAccesible=T|IndexInSheet=23|OwnerPartId=1|Location.X=1092|Location.X_Frac=50000|Location.Y=735|Corner.X=1092|Corner.X_Frac=50000|Corner.Y=725|LineWidth=1|Color=16711680
|RECORD=41|OwnerIndex=244|IndexInSheet=24|OwnerPartId=-1|Location.X=1078|Location.Y=736|Color=8388608|FontID=1|IsHidden=T|Text=<VALENTIUM>|Name=VALENTIUM PART NUM
|RECORD=34|OwnerIndex=244|IndexInSheet=-1|OwnerPartId=-1|Location.X=1070|Location.Y=716|Color=8388608|FontID=1|Text=C49|Name=Designator|ReadOnlyState=1
|RECORD=41|OwnerIndex=244|IndexInSheet=-1|OwnerPartId=-1|Location.X=1078|Location.Y=736|Color=8388608|FontID=1|IsHidden=T|Text=CAP_0402_0.1UF_50V|Name=Comment|ReadOnlyState=1
|RECORD=44|OwnerIndex=244
|RECORD=45|OwnerIndex=274|IndexInSheet=-1|Description=Chip Capacitor, 0402, 2-Leads, Body 1.00x0.50mm, IPC Medium Density|UseComponentLibrary=T|ModelName=CAPC1005X06N|ModelType=PCBLIB|DatafileCount=1|ModelDatafileEntity0=CAPC1005X06N|ModelDatafileKind0=PCBLib|IsCurrent=T|DatalinksLocked=T|DatabaseDatalinksLocked=T|IntegratedModel=T|DatabaseModel=T
|RECORD=46|OwnerIndex=275
|RECORD=48|OwnerIndex=275
|RECORD=1|LibReference=CAP_0402_0.1UF_50V|ComponentDescription=CAP, CER, 0.1UF, 50V, 10%, X7R, AEC-Q200, 0402|PartCount=2|DisplayModeCount=1|IndexInSheet=40|OwnerPartId=-1|Location.X=1130|Location.Y=760|Orientation=1|CurrentPartId=1|LibraryPath=*|SourceLibraryName=Capacitors.IntLib|TargetFileName=*|AreaColor=11599871|Color=128|PartIDLocked=F|DesignItemId=CAP_0402_0.1UF_50V|AllPinCount=2
|RECORD=41|OwnerIndex=278|OwnerPartId=-1|Location.X=1078|Location.Y=786|Color=8388608|FontID=8|IsHidden=T|Text=CAP, CER|Name=CATEGORY
|RECORD=41|OwnerIndex=278|IndexInSheet=1|OwnerPartId=-1|Location.X=1078|Location.Y=786|Color=8388608|FontID=8|IsHidden=T|Text=TDK|Name=MFG NAME
|RECORD=41|OwnerIndex=278|IndexInSheet=2|OwnerPartId=-1|Location.X=1078|Location.Y=786|Color=8388608|FontID=8|IsHidden=T|Text=CGA2B3X7R1H104K050BB|Name=MFG PART NUM
|RECORD=41|OwnerIndex=278|IndexInSheet=3|OwnerPartId=-1|Location.X=1078|Location.Y=786|Color=8388608|FontID=8|IsHidden=T|Text=10/23/2013|Name=MODIFY DATE
|RECORD=41|OwnerIndex=278|IndexInSheet=4|OwnerPartId=-1|Location.X=1078|Location.Y=786|Color=8388608|FontID=8|IsHidden=T|Name=Date
|RECORD=41|OwnerIndex=278|IndexInSheet=5|OwnerPartId=-1|Location.X=1078|Location.Y=786|Color=8388608|FontID=8|IsHidden=T|Text=*|Name=SHEETPART
|RECORD=41|OwnerIndex=278|IndexInSheet=6|OwnerPartId=-1|Location.X=1078|Location.Y=786|Color=8388608|FontID=8|IsHidden=T|Text=10%|Name=P1
|RECORD=41|OwnerIndex=278|IndexInSheet=7|OwnerPartId=-1|Location.X=1078|Location.Y=786|Color=8388608|FontID=8|IsHidden=T|Text=125C|Name=MAXTEMP
|RECORD=41|OwnerIndex=278|IndexInSheet=8|OwnerPartId=-1|Location.X=1078|Location.Y=786|Color=8388608|FontID=8|IsHidden=T|Text=-55C|Name=MINTEMP
|RECORD=41|OwnerIndex=278|IndexInSheet=9|OwnerPartId=-1|Location.X=1078|Location.Y=786|Color=8388608|FontID=8|IsHidden=T|Text=AEC-Q200|Name=OTHER
|RECORD=41|OwnerIndex=278|IndexInSheet=10|OwnerPartId=-1|Location.X=1078|Location.Y=786|Color=8388608|FontID=8|IsHidden=T|Text=50V|Name=P2
|RECORD=41|OwnerIndex=278|IndexInSheet=11|OwnerPartId=-1|Location.X=1078|Location.Y=786|Color=8388608|FontID=8|IsHidden=T|Text=X7R|Name=P3
|RECORD=41|OwnerIndex=278|IndexInSheet=12|OwnerPartId=-1|Location.X=1078|Location.Y=786|Color=8388608|FontID=8|IsHidden=T|Text=0402|Name=Size
|RECORD=41|OwnerIndex=278|IndexInSheet=13|OwnerPartId=-1|Location.X=1078|Location.Y=786|Color=8388608|FontID=8|IsHidden=T|Name=SUB
|RECORD=41|OwnerIndex=278|IndexInSheet=14|OwnerPartId=-1|Location.X=1078|Location.Y=786|Color=8388608|FontID=1|IsHidden=T|Text=CAP, CER, 0.1UF, 50V, 10%, X7R, AEC-Q200, 0402|Name=DESC
|RECORD=41|OwnerIndex=278|IndexInSheet=15|OwnerPartId=-1|Location.X=1078|Location.Y=786|Color=8388608|FontID=1|IsHidden=T|Text=Digi-Key|Name=Supplier 1|ReadOnlyState=3
|RECORD=41|OwnerIndex=278|IndexInSheet=16|OwnerPartId=-1|Location.X=1078|Location.Y=786|Color=8388608|FontID=1|IsHidden=T|Text=445-6899-1-ND|Name=Supplier Part Number 1|ReadOnlyState=3
|RECORD=41|OwnerIndex=278|IndexInSheet=17|OwnerPartId=-1|Location.X=1101|Location.Y=768|Color=8388608|FontID=8|Text=0.1UF|Name=VALUE
|RECORD=2|OwnerIndex=278|OwnerPartId=1|FormalType=1|Electrical=4|PinConglomerate=32|PinLength=10|Location.X=1100|Location.Y=780|Name=2|Designator=2|SwapIdPin=2|SwapIDPart=1|PinPropagationDelay=0.000000E+000
|RECORD=2|OwnerIndex=278|OwnerPartId=1|FormalType=1|Electrical=4|PinConglomerate=34|PinLength=10|Location.X=1090|Location.Y=780|Name=1|Designator=1|SwapIdPin=1|SwapIDPart=1|PinPropagationDelay=0.000000E+000
|RECORD=13|OwnerIndex=278|IsNotAccesible=T|IndexInSheet=20|OwnerPartId=1|Location.X=1097|Location.X_Frac=50000|Location.Y=780|Corner.X=1100|Corner.Y=780|LineWidth=1|Color=16711680
|RECORD=13|OwnerIndex=278|IsNotAccesible=T|IndexInSheet=21|OwnerPartId=1|Location.X=1090|Location.Y=780|Corner.X=1092|Corner.X_Frac=50000|Corner.Y=780|LineWidth=1|Color=16711680
|RECORD=13|OwnerIndex=278|IsNotAccesible=T|IndexInSheet=22|OwnerPartId=1|Location.X=1097|Location.X_Frac=50000|Location.Y=785|Corner.X=1097|Corner.X_Frac=50000|Corner.Y=775|LineWidth=1|Color=16711680
|RECORD=13|OwnerIndex=278|IsNotAccesible=T|IndexInSheet=23|OwnerPartId=1|Location.X=1092|Location.X_Frac=50000|Location.Y=785|Corner.X=1092|Corner.X_Frac=50000|Corner.Y=775|LineWidth=1|Color=16711680
|RECORD=41|OwnerIndex=278|IndexInSheet=24|OwnerPartId=-1|Location.X=1078|Location.Y=786|Color=8388608|FontID=1|IsHidden=T|Text=<VALENTIUM>|Name=VALENTIUM PART NUM
|RECORD=34|OwnerIndex=278|IndexInSheet=-1|OwnerPartId=-1|Location.X=1070|Location.Y=766|Color=8388608|FontID=1|Text=C47|Name=Designator|ReadOnlyState=1
|RECORD=41|OwnerIndex=278|IndexInSheet=-1|OwnerPartId=-1|Location.X=1078|Location.Y=786|Color=8388608|FontID=1|IsHidden=T|Text=CAP_0402_0.1UF_50V|Name=Comment|ReadOnlyState=1
|RECORD=44|OwnerIndex=278
|RECORD=45|OwnerIndex=308|IndexInSheet=-1|Description=Chip Capacitor, 0402, 2-Leads, Body 1.00x0.50mm, IPC Medium Density|UseComponentLibrary=T|ModelName=CAPC1005X06N|ModelType=PCBLIB|DatafileCount=1|ModelDatafileEntity0=CAPC1005X06N|ModelDatafileKind0=PCBLib|IsCurrent=T|DatalinksLocked=T|DatabaseDatalinksLocked=T|IntegratedModel=T|DatabaseModel=T
|RECORD=46|OwnerIndex=309
|RECORD=48|OwnerIndex=309
|RECORD=1|LibReference=CAP_0402_0.1UF_50V|ComponentDescription=CAP, CER, 0.1UF, 50V, 10%, X7R, AEC-Q200, 0402|PartCount=2|DisplayModeCount=1|IndexInSheet=41|OwnerPartId=-1|Location.X=1130|Location.Y=790|Orientation=1|CurrentPartId=1|LibraryPath=*|SourceLibraryName=Capacitors.IntLib|TargetFileName=*|AreaColor=11599871|Color=128|PartIDLocked=F|DesignItemId=CAP_0402_0.1UF_50V|AllPinCount=2
|RECORD=41|OwnerIndex=312|OwnerPartId=-1|Location.X=1078|Location.Y=816|Color=8388608|FontID=8|IsHidden=T|Text=CAP, CER|Name=CATEGORY
|RECORD=41|OwnerIndex=312|IndexInSheet=1|OwnerPartId=-1|Location.X=1078|Location.Y=816|Color=8388608|FontID=8|IsHidden=T|Text=TDK|Name=MFG NAME
|RECORD=41|OwnerIndex=312|IndexInSheet=2|OwnerPartId=-1|Location.X=1078|Location.Y=816|Color=8388608|FontID=8|IsHidden=T|Text=CGA2B3X7R1H104K050BB|Name=MFG PART NUM
|RECORD=41|OwnerIndex=312|IndexInSheet=3|OwnerPartId=-1|Location.X=1078|Location.Y=816|Color=8388608|FontID=8|IsHidden=T|Text=10/23/2013|Name=MODIFY DATE
|RECORD=41|OwnerIndex=312|IndexInSheet=4|OwnerPartId=-1|Location.X=1078|Location.Y=816|Color=8388608|FontID=8|IsHidden=T|Name=Date
|RECORD=41|OwnerIndex=312|IndexInSheet=5|OwnerPartId=-1|Location.X=1078|Location.Y=816|Color=8388608|FontID=8|IsHidden=T|Text=*|Name=SHEETPART
|RECORD=41|OwnerIndex=312|IndexInSheet=6|OwnerPartId=-1|Location.X=1078|Location.Y=816|Color=8388608|FontID=8|IsHidden=T|Text=10%|Name=P1
|RECORD=41|OwnerIndex=312|IndexInSheet=7|OwnerPartId=-1|Location.X=1078|Location.Y=816|Color=8388608|FontID=8|IsHidden=T|Text=125C|Name=MAXTEMP
|RECORD=41|OwnerIndex=312|IndexInSheet=8|OwnerPartId=-1|Location.X=1078|Location.Y=816|Color=8388608|FontID=8|IsHidden=T|Text=-55C|Name=MINTEMP
|RECORD=41|OwnerIndex=312|IndexInSheet=9|OwnerPartId=-1|Location.X=1078|Location.Y=816|Color=8388608|FontID=8|IsHidden=T|Text=AEC-Q200|Name=OTHER
|RECORD=41|OwnerIndex=312|IndexInSheet=10|OwnerPartId=-1|Location.X=1078|Location.Y=816|Color=8388608|FontID=8|IsHidden=T|Text=50V|Name=P2
|RECORD=41|OwnerIndex=312|IndexInSheet=11|OwnerPartId=-1|Location.X=1078|Location.Y=816|Color=8388608|FontID=8|IsHidden=T|Text=X7R|Name=P3
|RECORD=41|OwnerIndex=312|IndexInSheet=12|OwnerPartId=-1|Location.X=1078|Location.Y=816|Color=8388608|FontID=8|IsHidden=T|Text=0402|Name=Size
|RECORD=41|OwnerIndex=312|IndexInSheet=13|OwnerPartId=-1|Location.X=1078|Location.Y=816|Color=8388608|FontID=8|IsHidden=T|Name=SUB
|RECORD=41|OwnerIndex=312|IndexInSheet=14|OwnerPartId=-1|Location.X=1078|Location.Y=816|Color=8388608|FontID=1|IsHidden=T|Text=CAP, CER, 0.1UF, 50V, 10%, X7R, AEC-Q200, 0402|Name=DESC
|RECORD=41|OwnerIndex=312|IndexInSheet=15|OwnerPartId=-1|Location.X=1078|Location.Y=816|Color=8388608|FontID=1|IsHidden=T|Text=Digi-Key|Name=Supplier 1|ReadOnlyState=3
|RECORD=41|OwnerIndex=312|IndexInSheet=16|OwnerPartId=-1|Location.X=1078|Location.Y=816|Color=8388608|FontID=1|IsHidden=T|Text=445-6899-1-ND|Name=Supplier Part Number 1|ReadOnlyState=3
|RECORD=41|OwnerIndex=312|IndexInSheet=17|OwnerPartId=-1|Location.X=1101|Location.Y=798|Color=8388608|FontID=8|Text=0.1UF|Name=VALUE
|RECORD=2|OwnerIndex=312|OwnerPartId=1|FormalType=1|Electrical=4|PinConglomerate=32|PinLength=10|Location.X=1100|Location.Y=810|Name=2|Designator=2|SwapIdPin=2|SwapIDPart=1|PinPropagationDelay=0.000000E+000
|RECORD=2|OwnerIndex=312|OwnerPartId=1|FormalType=1|Electrical=4|PinConglomerate=34|PinLength=10|Location.X=1090|Location.Y=810|Name=1|Designator=1|SwapIdPin=1|SwapIDPart=1|PinPropagationDelay=0.000000E+000
|RECORD=13|OwnerIndex=312|IsNotAccesible=T|IndexInSheet=20|OwnerPartId=1|Location.X=1097|Location.X_Frac=50000|Location.Y=810|Corner.X=1100|Corner.Y=810|LineWidth=1|Color=16711680
|RECORD=13|OwnerIndex=312|IsNotAccesible=T|IndexInSheet=21|OwnerPartId=1|Location.X=1090|Location.Y=810|Corner.X=1092|Corner.X_Frac=50000|Corner.Y=810|LineWidth=1|Color=16711680
|RECORD=13|OwnerIndex=312|IsNotAccesible=T|IndexInSheet=22|OwnerPartId=1|Location.X=1097|Location.X_Frac=50000|Location.Y=815|Corner.X=1097|Corner.X_Frac=50000|Corner.Y=805|LineWidth=1|Color=16711680
|RECORD=13|OwnerIndex=312|IsNotAccesible=T|IndexInSheet=23|OwnerPartId=1|Location.X=1092|Location.X_Frac=50000|Location.Y=815|Corner.X=1092|Corner.X_Frac=50000|Corner.Y=805|LineWidth=1|Color=16711680
|RECORD=41|OwnerIndex=312|IndexInSheet=24|OwnerPartId=-1|Location.X=1078|Location.Y=816|Color=8388608|FontID=1|IsHidden=T|Text=<VALENTIUM>|Name=VALENTIUM PART NUM
|RECORD=34|OwnerIndex=312|IndexInSheet=-1|OwnerPartId=-1|Location.X=1070|Location.Y=796|Color=8388608|FontID=1|Text=C45|Name=Designator|ReadOnlyState=1
|RECORD=41|OwnerIndex=312|IndexInSheet=-1|OwnerPartId=-1|Location.X=1078|Location.Y=816|Color=8388608|FontID=1|IsHidden=T|Text=CAP_0402_0.1UF_50V|Name=Comment|ReadOnlyState=1
|RECORD=44|OwnerIndex=312
|RECORD=45|OwnerIndex=342|IndexInSheet=-1|Description=Chip Capacitor, 0402, 2-Leads, Body 1.00x0.50mm, IPC Medium Density|UseComponentLibrary=T|ModelName=CAPC1005X06N|ModelType=PCBLIB|DatafileCount=1|ModelDatafileEntity0=CAPC1005X06N|ModelDatafileKind0=PCBLib|IsCurrent=T|DatalinksLocked=T|DatabaseDatalinksLocked=T|IntegratedModel=T|DatabaseModel=T
|RECORD=46|OwnerIndex=343
|RECORD=48|OwnerIndex=343
|RECORD=1|LibReference=CAP_0402_0.1UF_50V|ComponentDescription=CAP, CER, 0.1UF, 50V, 10%, X7R, AEC-Q200, 0402|PartCount=2|DisplayModeCount=1|IndexInSheet=42|OwnerPartId=-1|Location.X=1090|Location.Y=800|Orientation=1|CurrentPartId=1|LibraryPath=*|SourceLibraryName=Capacitors.IntLib|TargetFileName=*|AreaColor=11599871|Color=128|PartIDLocked=F|DesignItemId=CAP_0402_0.1UF_50V|AllPinCount=2
|RECORD=41|OwnerIndex=346|OwnerPartId=-1|Location.X=1038|Location.Y=826|Color=8388608|FontID=8|IsHidden=T|Text=CAP, CER|Name=CATEGORY
|RECORD=41|OwnerIndex=346|IndexInSheet=1|OwnerPartId=-1|Location.X=1038|Location.Y=826|Color=8388608|FontID=8|IsHidden=T|Text=TDK|Name=MFG NAME
|RECORD=41|OwnerIndex=346|IndexInSheet=2|OwnerPartId=-1|Location.X=1038|Location.Y=826|Color=8388608|FontID=8|IsHidden=T|Text=CGA2B3X7R1H104K050BB|Name=MFG PART NUM
|RECORD=41|OwnerIndex=346|IndexInSheet=3|OwnerPartId=-1|Location.X=1038|Location.Y=826|Color=8388608|FontID=8|IsHidden=T|Text=10/23/2013|Name=MODIFY DATE
|RECORD=41|OwnerIndex=346|IndexInSheet=4|OwnerPartId=-1|Location.X=1038|Location.Y=826|Color=8388608|FontID=8|IsHidden=T|Name=Date
|RECORD=41|OwnerIndex=346|IndexInSheet=5|OwnerPartId=-1|Location.X=1038|Location.Y=826|Color=8388608|FontID=8|IsHidden=T|Text=*|Name=SHEETPART
|RECORD=41|OwnerIndex=346|IndexInSheet=6|OwnerPartId=-1|Location.X=1038|Location.Y=826|Color=8388608|FontID=8|IsHidden=T|Text=10%|Name=P1
|RECORD=41|OwnerIndex=346|IndexInSheet=7|OwnerPartId=-1|Location.X=1038|Location.Y=826|Color=8388608|FontID=8|IsHidden=T|Text=125C|Name=MAXTEMP
|RECORD=41|OwnerIndex=346|IndexInSheet=8|OwnerPartId=-1|Location.X=1038|Location.Y=826|Color=8388608|FontID=8|IsHidden=T|Text=-55C|Name=MINTEMP
|RECORD=41|OwnerIndex=346|IndexInSheet=9|OwnerPartId=-1|Location.X=1038|Location.Y=826|Color=8388608|FontID=8|IsHidden=T|Text=AEC-Q200|Name=OTHER
|RECORD=41|OwnerIndex=346|IndexInSheet=10|OwnerPartId=-1|Location.X=1038|Location.Y=826|Color=8388608|FontID=8|IsHidden=T|Text=50V|Name=P2
|RECORD=41|OwnerIndex=346|IndexInSheet=11|OwnerPartId=-1|Location.X=1038|Location.Y=826|Color=8388608|FontID=8|IsHidden=T|Text=X7R|Name=P3
|RECORD=41|OwnerIndex=346|IndexInSheet=12|OwnerPartId=-1|Location.X=1038|Location.Y=826|Color=8388608|FontID=8|IsHidden=T|Text=0402|Name=Size
|RECORD=41|OwnerIndex=346|IndexInSheet=13|OwnerPartId=-1|Location.X=1038|Location.Y=826|Color=8388608|FontID=8|IsHidden=T|Name=SUB
|RECORD=41|OwnerIndex=346|IndexInSheet=14|OwnerPartId=-1|Location.X=1038|Location.Y=826|Color=8388608|FontID=1|IsHidden=T|Text=CAP, CER, 0.1UF, 50V, 10%, X7R, AEC-Q200, 0402|Name=DESC
|RECORD=41|OwnerIndex=346|IndexInSheet=15|OwnerPartId=-1|Location.X=1038|Location.Y=826|Color=8388608|FontID=1|IsHidden=T|Text=Digi-Key|Name=Supplier 1|ReadOnlyState=3
|RECORD=41|OwnerIndex=346|IndexInSheet=16|OwnerPartId=-1|Location.X=1038|Location.Y=826|Color=8388608|FontID=1|IsHidden=T|Text=445-6899-1-ND|Name=Supplier Part Number 1|ReadOnlyState=3
|RECORD=41|OwnerIndex=346|IndexInSheet=17|OwnerPartId=-1|Location.X=1060|Location.Y=820|Color=8388608|FontID=8|Text=0.1UF|Name=VALUE
|RECORD=2|OwnerIndex=346|OwnerPartId=1|FormalType=1|Electrical=4|PinConglomerate=32|PinLength=10|Location.X=1060|Location.Y=820|Name=2|Designator=2|SwapIdPin=2|SwapIDPart=1|PinPropagationDelay=0.000000E+000
|RECORD=2|OwnerIndex=346|OwnerPartId=1|FormalType=1|Electrical=4|PinConglomerate=34|PinLength=10|Location.X=1050|Location.Y=820|Name=1|Designator=1|SwapIdPin=1|SwapIDPart=1|PinPropagationDelay=0.000000E+000
|RECORD=13|OwnerIndex=346|IsNotAccesible=T|IndexInSheet=20|OwnerPartId=1|Location.X=1057|Location.X_Frac=50000|Location.Y=820|Corner.X=1060|Corner.Y=820|LineWidth=1|Color=16711680
|RECORD=13|OwnerIndex=346|IsNotAccesible=T|IndexInSheet=21|OwnerPartId=1|Location.X=1050|Location.Y=820|Corner.X=1052|Corner.X_Frac=50000|Corner.Y=820|LineWidth=1|Color=16711680
|RECORD=13|OwnerIndex=346|IsNotAccesible=T|IndexInSheet=22|OwnerPartId=1|Location.X=1057|Location.X_Frac=50000|Location.Y=825|Corner.X=1057|Corner.X_Frac=50000|Corner.Y=815|LineWidth=1|Color=16711680
|RECORD=13|OwnerIndex=346|IsNotAccesible=T|IndexInSheet=23|OwnerPartId=1|Location.X=1052|Location.X_Frac=50000|Location.Y=825|Corner.X=1052|Corner.X_Frac=50000|Corner.Y=815|LineWidth=1|Color=16711680
|RECORD=41|OwnerIndex=346|IndexInSheet=24|OwnerPartId=-1|Location.X=1038|Location.Y=826|Color=8388608|FontID=1|IsHidden=T|Text=<VALENTIUM>|Name=VALENTIUM PART NUM
|RECORD=34|OwnerIndex=346|IndexInSheet=-1|OwnerPartId=-1|Location.X=1030|Location.Y=820|Color=8388608|FontID=1|Text=C44|Name=Designator|ReadOnlyState=1
|RECORD=41|OwnerIndex=346|IndexInSheet=-1|OwnerPartId=-1|Location.X=1038|Location.Y=826|Color=8388608|FontID=1|IsHidden=T|Text=CAP_0402_0.1UF_50V|Name=Comment|ReadOnlyState=1
|RECORD=44|OwnerIndex=346
|RECORD=45|OwnerIndex=376|IndexInSheet=-1|Description=Chip Capacitor, 0402, 2-Leads, Body 1.00x0.50mm, IPC Medium Density|UseComponentLibrary=T|ModelName=CAPC1005X06N|ModelType=PCBLIB|DatafileCount=1|ModelDatafileEntity0=CAPC1005X06N|ModelDatafileKind0=PCBLib|IsCurrent=T|DatalinksLocked=T|DatabaseDatalinksLocked=T|IntegratedModel=T|DatabaseModel=T
|RECORD=46|OwnerIndex=377
|RECORD=48|OwnerIndex=377
|RECORD=1|LibReference=CAP_0402_0.1UF_50V|ComponentDescription=CAP, CER, 0.1UF, 50V, 10%, X7R, AEC-Q200, 0402|PartCount=2|DisplayModeCount=1|IndexInSheet=43|OwnerPartId=-1|Location.X=1060|Location.Y=770|Orientation=1|CurrentPartId=1|LibraryPath=*|SourceLibraryName=Capacitors.IntLib|TargetFileName=*|AreaColor=11599871|Color=128|PartIDLocked=F|DesignItemId=CAP_0402_0.1UF_50V|AllPinCount=2
|RECORD=41|OwnerIndex=380|OwnerPartId=-1|Location.X=1008|Location.Y=796|Color=8388608|FontID=8|IsHidden=T|Text=CAP, CER|Name=CATEGORY
|RECORD=41|OwnerIndex=380|IndexInSheet=1|OwnerPartId=-1|Location.X=1008|Location.Y=796|Color=8388608|FontID=8|IsHidden=T|Text=TDK|Name=MFG NAME
|RECORD=41|OwnerIndex=380|IndexInSheet=2|OwnerPartId=-1|Location.X=1008|Location.Y=796|Color=8388608|FontID=8|IsHidden=T|Text=CGA2B3X7R1H104K050BB|Name=MFG PART NUM
|RECORD=41|OwnerIndex=380|IndexInSheet=3|OwnerPartId=-1|Location.X=1008|Location.Y=796|Color=8388608|FontID=8|IsHidden=T|Text=10/23/2013|Name=MODIFY DATE
|RECORD=41|OwnerIndex=380|IndexInSheet=4|OwnerPartId=-1|Location.X=1008|Location.Y=796|Color=8388608|FontID=8|IsHidden=T|Name=Date
|RECORD=41|OwnerIndex=380|IndexInSheet=5|OwnerPartId=-1|Location.X=1008|Location.Y=796|Color=8388608|FontID=8|IsHidden=T|Text=*|Name=SHEETPART
|RECORD=41|OwnerIndex=380|IndexInSheet=6|OwnerPartId=-1|Location.X=1008|Location.Y=796|Color=8388608|FontID=8|IsHidden=T|Text=10%|Name=P1
|RECORD=41|OwnerIndex=380|IndexInSheet=7|OwnerPartId=-1|Location.X=1008|Location.Y=796|Color=8388608|FontID=8|IsHidden=T|Text=125C|Name=MAXTEMP
|RECORD=41|OwnerIndex=380|IndexInSheet=8|OwnerPartId=-1|Location.X=1008|Location.Y=796|Color=8388608|FontID=8|IsHidden=T|Text=-55C|Name=MINTEMP
|RECORD=41|OwnerIndex=380|IndexInSheet=9|OwnerPartId=-1|Location.X=1008|Location.Y=796|Color=8388608|FontID=8|IsHidden=T|Text=AEC-Q200|Name=OTHER
|RECORD=41|OwnerIndex=380|IndexInSheet=10|OwnerPartId=-1|Location.X=1008|Location.Y=796|Color=8388608|FontID=8|IsHidden=T|Text=50V|Name=P2
|RECORD=41|OwnerIndex=380|IndexInSheet=11|OwnerPartId=-1|Location.X=1008|Location.Y=796|Color=8388608|FontID=8|IsHidden=T|Text=X7R|Name=P3
|RECORD=41|OwnerIndex=380|IndexInSheet=12|OwnerPartId=-1|Location.X=1008|Location.Y=796|Color=8388608|FontID=8|IsHidden=T|Text=0402|Name=Size
|RECORD=41|OwnerIndex=380|IndexInSheet=13|OwnerPartId=-1|Location.X=1008|Location.Y=796|Color=8388608|FontID=8|IsHidden=T|Name=SUB
|RECORD=41|OwnerIndex=380|IndexInSheet=14|OwnerPartId=-1|Location.X=1008|Location.Y=796|Color=8388608|FontID=1|IsHidden=T|Text=CAP, CER, 0.1UF, 50V, 10%, X7R, AEC-Q200, 0402|Name=DESC
|RECORD=41|OwnerIndex=380|IndexInSheet=15|OwnerPartId=-1|Location.X=1008|Location.Y=796|Color=8388608|FontID=1|IsHidden=T|Text=Digi-Key|Name=Supplier 1|ReadOnlyState=3
|RECORD=41|OwnerIndex=380|IndexInSheet=16|OwnerPartId=-1|Location.X=1008|Location.Y=796|Color=8388608|FontID=1|IsHidden=T|Text=445-6899-1-ND|Name=Supplier Part Number 1|ReadOnlyState=3
|RECORD=41|OwnerIndex=380|IndexInSheet=17|OwnerPartId=-1|Location.X=1030|Location.Y=790|Color=8388608|FontID=8|Text=0.1UF|Name=VALUE
|RECORD=2|OwnerIndex=380|OwnerPartId=1|FormalType=1|Electrical=4|PinConglomerate=32|PinLength=10|Location.X=1030|Location.Y=790|Name=2|Designator=2|SwapIdPin=2|SwapIDPart=1|PinPropagationDelay=0.000000E+000
|RECORD=2|OwnerIndex=380|OwnerPartId=1|FormalType=1|Electrical=4|PinConglomerate=34|PinLength=10|Location.X=1020|Location.Y=790|Name=1|Designator=1|SwapIdPin=1|SwapIDPart=1|PinPropagationDelay=0.000000E+000
|RECORD=13|OwnerIndex=380|IsNotAccesible=T|IndexInSheet=20|OwnerPartId=1|Location.X=1027|Location.X_Frac=50000|Location.Y=790|Corner.X=1030|Corner.Y=790|LineWidth=1|Color=16711680
|RECORD=13|OwnerIndex=380|IsNotAccesible=T|IndexInSheet=21|OwnerPartId=1|Location.X=1020|Location.Y=790|Corner.X=1022|Corner.X_Frac=50000|Corner.Y=790|LineWidth=1|Color=16711680
|RECORD=13|OwnerIndex=380|IsNotAccesible=T|IndexInSheet=22|OwnerPartId=1|Location.X=1027|Location.X_Frac=50000|Location.Y=795|Corner.X=1027|Corner.X_Frac=50000|Corner.Y=785|LineWidth=1|Color=16711680
|RECORD=13|OwnerIndex=380|IsNotAccesible=T|IndexInSheet=23|OwnerPartId=1|Location.X=1022|Location.X_Frac=50000|Location.Y=795|Corner.X=1022|Corner.X_Frac=50000|Corner.Y=785|LineWidth=1|Color=16711680
|RECORD=41|OwnerIndex=380|IndexInSheet=24|OwnerPartId=-1|Location.X=1008|Location.Y=796|Color=8388608|FontID=1|IsHidden=T|Text=<VALENTIUM>|Name=VALENTIUM PART NUM
|RECORD=34|OwnerIndex=380|IndexInSheet=-1|OwnerPartId=-1|Location.X=1000|Location.Y=790|Color=8388608|FontID=1|Text=C46|Name=Designator|ReadOnlyState=1
|RECORD=41|OwnerIndex=380|IndexInSheet=-1|OwnerPartId=-1|Location.X=1008|Location.Y=796|Color=8388608|FontID=1|IsHidden=T|Text=CAP_0402_0.1UF_50V|Name=Comment|ReadOnlyState=1
|RECORD=44|OwnerIndex=380
|RECORD=45|OwnerIndex=410|IndexInSheet=-1|Description=Chip Capacitor, 0402, 2-Leads, Body 1.00x0.50mm, IPC Medium Density|UseComponentLibrary=T|ModelName=CAPC1005X06N|ModelType=PCBLIB|DatafileCount=1|ModelDatafileEntity0=CAPC1005X06N|ModelDatafileKind0=PCBLib|IsCurrent=T|DatalinksLocked=T|DatabaseDatalinksLocked=T|IntegratedModel=T|DatabaseModel=T
|RECORD=46|OwnerIndex=411
|RECORD=48|OwnerIndex=411
|RECORD=1|LibReference=CAP_0402_0.1UF_50V|ComponentDescription=CAP, CER, 0.1UF, 50V, 10%, X7R, AEC-Q200, 0402|PartCount=2|DisplayModeCount=1|IndexInSheet=44|OwnerPartId=-1|Location.X=1090|Location.Y=720|Orientation=1|CurrentPartId=1|LibraryPath=*|SourceLibraryName=Capacitors.IntLib|TargetFileName=*|AreaColor=11599871|Color=128|PartIDLocked=F|DesignItemId=CAP_0402_0.1UF_50V|AllPinCount=2
|RECORD=41|OwnerIndex=414|OwnerPartId=-1|Location.X=1038|Location.Y=746|Color=8388608|FontID=8|IsHidden=T|Text=CAP, CER|Name=CATEGORY
|RECORD=41|OwnerIndex=414|IndexInSheet=1|OwnerPartId=-1|Location.X=1038|Location.Y=746|Color=8388608|FontID=8|IsHidden=T|Text=TDK|Name=MFG NAME
|RECORD=41|OwnerIndex=414|IndexInSheet=2|OwnerPartId=-1|Location.X=1038|Location.Y=746|Color=8388608|FontID=8|IsHidden=T|Text=CGA2B3X7R1H104K050BB|Name=MFG PART NUM
|RECORD=41|OwnerIndex=414|IndexInSheet=3|OwnerPartId=-1|Location.X=1038|Location.Y=746|Color=8388608|FontID=8|IsHidden=T|Text=10/23/2013|Name=MODIFY DATE
|RECORD=41|OwnerIndex=414|IndexInSheet=4|OwnerPartId=-1|Location.X=1038|Location.Y=746|Color=8388608|FontID=8|IsHidden=T|Name=Date
|RECORD=41|OwnerIndex=414|IndexInSheet=5|OwnerPartId=-1|Location.X=1038|Location.Y=746|Color=8388608|FontID=8|IsHidden=T|Text=*|Name=SHEETPART
|RECORD=41|OwnerIndex=414|IndexInSheet=6|OwnerPartId=-1|Location.X=1038|Location.Y=746|Color=8388608|FontID=8|IsHidden=T|Text=10%|Name=P1
|RECORD=41|OwnerIndex=414|IndexInSheet=7|OwnerPartId=-1|Location.X=1038|Location.Y=746|Color=8388608|FontID=8|IsHidden=T|Text=125C|Name=MAXTEMP
|RECORD=41|OwnerIndex=414|IndexInSheet=8|OwnerPartId=-1|Location.X=1038|Location.Y=746|Color=8388608|FontID=8|IsHidden=T|Text=-55C|Name=MINTEMP
|RECORD=41|OwnerIndex=414|IndexInSheet=9|OwnerPartId=-1|Location.X=1038|Location.Y=746|Color=8388608|FontID=8|IsHidden=T|Text=AEC-Q200|Name=OTHER
|RECORD=41|OwnerIndex=414|IndexInSheet=10|OwnerPartId=-1|Location.X=1038|Location.Y=746|Color=8388608|FontID=8|IsHidden=T|Text=50V|Name=P2
|RECORD=41|OwnerIndex=414|IndexInSheet=11|OwnerPartId=-1|Location.X=1038|Location.Y=746|Color=8388608|FontID=8|IsHidden=T|Text=X7R|Name=P3
|RECORD=41|OwnerIndex=414|IndexInSheet=12|OwnerPartId=-1|Location.X=1038|Location.Y=746|Color=8388608|FontID=8|IsHidden=T|Text=0402|Name=Size
|RECORD=41|OwnerIndex=414|IndexInSheet=13|OwnerPartId=-1|Location.X=1038|Location.Y=746|Color=8388608|FontID=8|IsHidden=T|Name=SUB
|RECORD=41|OwnerIndex=414|IndexInSheet=14|OwnerPartId=-1|Location.X=1038|Location.Y=746|Color=8388608|FontID=1|IsHidden=T|Text=CAP, CER, 0.1UF, 50V, 10%, X7R, AEC-Q200, 0402|Name=DESC
|RECORD=41|OwnerIndex=414|IndexInSheet=15|OwnerPartId=-1|Location.X=1038|Location.Y=746|Color=8388608|FontID=1|IsHidden=T|Text=Digi-Key|Name=Supplier 1|ReadOnlyState=3
|RECORD=41|OwnerIndex=414|IndexInSheet=16|OwnerPartId=-1|Location.X=1038|Location.Y=746|Color=8388608|FontID=1|IsHidden=T|Text=445-6899-1-ND|Name=Supplier Part Number 1|ReadOnlyState=3
|RECORD=41|OwnerIndex=414|IndexInSheet=17|OwnerPartId=-1|Location.X=1060|Location.Y=740|Color=8388608|FontID=8|Text=0.1UF|Name=VALUE
|RECORD=2|OwnerIndex=414|OwnerPartId=1|FormalType=1|Electrical=4|PinConglomerate=32|PinLength=10|Location.X=1060|Location.Y=740|Name=2|Designator=2|SwapIdPin=2|SwapIDPart=1|PinPropagationDelay=0.000000E+000
|RECORD=2|OwnerIndex=414|OwnerPartId=1|FormalType=1|Electrical=4|PinConglomerate=34|PinLength=10|Location.X=1050|Location.Y=740|Name=1|Designator=1|SwapIdPin=1|SwapIDPart=1|PinPropagationDelay=0.000000E+000
|RECORD=13|OwnerIndex=414|IsNotAccesible=T|IndexInSheet=20|OwnerPartId=1|Location.X=1057|Location.X_Frac=50000|Location.Y=740|Corner.X=1060|Corner.Y=740|LineWidth=1|Color=16711680
|RECORD=13|OwnerIndex=414|IsNotAccesible=T|IndexInSheet=21|OwnerPartId=1|Location.X=1050|Location.Y=740|Corner.X=1052|Corner.X_Frac=50000|Corner.Y=740|LineWidth=1|Color=16711680
|RECORD=13|OwnerIndex=414|IsNotAccesible=T|IndexInSheet=22|OwnerPartId=1|Location.X=1057|Location.X_Frac=50000|Location.Y=745|Corner.X=1057|Corner.X_Frac=50000|Corner.Y=735|LineWidth=1|Color=16711680
|RECORD=13|OwnerIndex=414|IsNotAccesible=T|IndexInSheet=23|OwnerPartId=1|Location.X=1052|Location.X_Frac=50000|Location.Y=745|Corner.X=1052|Corner.X_Frac=50000|Corner.Y=735|LineWidth=1|Color=16711680
|RECORD=41|OwnerIndex=414|IndexInSheet=24|OwnerPartId=-1|Location.X=1038|Location.Y=746|Color=8388608|FontID=1|IsHidden=T|Text=<VALENTIUM>|Name=VALENTIUM PART NUM
|RECORD=34|OwnerIndex=414|IndexInSheet=-1|OwnerPartId=-1|Location.X=1030|Location.Y=740|Color=8388608|FontID=1|Text=C48|Name=Designator|ReadOnlyState=1
|RECORD=41|OwnerIndex=414|IndexInSheet=-1|OwnerPartId=-1|Location.X=1038|Location.Y=746|Color=8388608|FontID=1|IsHidden=T|Text=CAP_0402_0.1UF_50V|Name=Comment|ReadOnlyState=1
|RECORD=44|OwnerIndex=414
|RECORD=45|OwnerIndex=444|IndexInSheet=-1|Description=Chip Capacitor, 0402, 2-Leads, Body 1.00x0.50mm, IPC Medium Density|UseComponentLibrary=T|ModelName=CAPC1005X06N|ModelType=PCBLIB|DatafileCount=1|ModelDatafileEntity0=CAPC1005X06N|ModelDatafileKind0=PCBLib|IsCurrent=T|DatalinksLocked=T|DatabaseDatalinksLocked=T|IntegratedModel=T|DatabaseModel=T
|RECORD=46|OwnerIndex=445
|RECORD=48|OwnerIndex=445
|RECORD=1|LibReference=CAP_0402_0.1UF_50V|ComponentDescription=CAP, CER, 0.1UF, 50V, 10%, X7R, AEC-Q200, 0402|PartCount=2|DisplayModeCount=1|IndexInSheet=45|OwnerPartId=-1|Location.X=1090|Location.Y=680|Orientation=1|CurrentPartId=1|LibraryPath=*|SourceLibraryName=Capacitors.IntLib|TargetFileName=*|AreaColor=11599871|Color=128|PartIDLocked=F|DesignItemId=CAP_0402_0.1UF_50V|AllPinCount=2
|RECORD=41|OwnerIndex=448|OwnerPartId=-1|Location.X=1038|Location.Y=706|Color=8388608|FontID=8|IsHidden=T|Text=CAP, CER|Name=CATEGORY
|RECORD=41|OwnerIndex=448|IndexInSheet=1|OwnerPartId=-1|Location.X=1038|Location.Y=706|Color=8388608|FontID=8|IsHidden=T|Text=TDK|Name=MFG NAME
|RECORD=41|OwnerIndex=448|IndexInSheet=2|OwnerPartId=-1|Location.X=1038|Location.Y=706|Color=8388608|FontID=8|IsHidden=T|Text=CGA2B3X7R1H104K050BB|Name=MFG PART NUM
|RECORD=41|OwnerIndex=448|IndexInSheet=3|OwnerPartId=-1|Location.X=1038|Location.Y=706|Color=8388608|FontID=8|IsHidden=T|Text=10/23/2013|Name=MODIFY DATE
|RECORD=41|OwnerIndex=448|IndexInSheet=4|OwnerPartId=-1|Location.X=1038|Location.Y=706|Color=8388608|FontID=8|IsHidden=T|Name=Date
|RECORD=41|OwnerIndex=448|IndexInSheet=5|OwnerPartId=-1|Location.X=1038|Location.Y=706|Color=8388608|FontID=8|IsHidden=T|Text=*|Name=SHEETPART
|RECORD=41|OwnerIndex=448|IndexInSheet=6|OwnerPartId=-1|Location.X=1038|Location.Y=706|Color=8388608|FontID=8|IsHidden=T|Text=10%|Name=P1
|RECORD=41|OwnerIndex=448|IndexInSheet=7|OwnerPartId=-1|Location.X=1038|Location.Y=706|Color=8388608|FontID=8|IsHidden=T|Text=125C|Name=MAXTEMP
|RECORD=41|OwnerIndex=448|IndexInSheet=8|OwnerPartId=-1|Location.X=1038|Location.Y=706|Color=8388608|FontID=8|IsHidden=T|Text=-55C|Name=MINTEMP
|RECORD=41|OwnerIndex=448|IndexInSheet=9|OwnerPartId=-1|Location.X=1038|Location.Y=706|Color=8388608|FontID=8|IsHidden=T|Text=AEC-Q200|Name=OTHER
|RECORD=41|OwnerIndex=448|IndexInSheet=10|OwnerPartId=-1|Location.X=1038|Location.Y=706|Color=8388608|FontID=8|IsHidden=T|Text=50V|Name=P2
|RECORD=41|OwnerIndex=448|IndexInSheet=11|OwnerPartId=-1|Location.X=1038|Location.Y=706|Color=8388608|FontID=8|IsHidden=T|Text=X7R|Name=P3
|RECORD=41|OwnerIndex=448|IndexInSheet=12|OwnerPartId=-1|Location.X=1038|Location.Y=706|Color=8388608|FontID=8|IsHidden=T|Text=0402|Name=Size
|RECORD=41|OwnerIndex=448|IndexInSheet=13|OwnerPartId=-1|Location.X=1038|Location.Y=706|Color=8388608|FontID=8|IsHidden=T|Name=SUB
|RECORD=41|OwnerIndex=448|IndexInSheet=14|OwnerPartId=-1|Location.X=1038|Location.Y=706|Color=8388608|FontID=1|IsHidden=T|Text=CAP, CER, 0.1UF, 50V, 10%, X7R, AEC-Q200, 0402|Name=DESC
|RECORD=41|OwnerIndex=448|IndexInSheet=15|OwnerPartId=-1|Location.X=1038|Location.Y=706|Color=8388608|FontID=1|IsHidden=T|Text=Digi-Key|Name=Supplier 1|ReadOnlyState=3
|RECORD=41|OwnerIndex=448|IndexInSheet=16|OwnerPartId=-1|Location.X=1038|Location.Y=706|Color=8388608|FontID=1|IsHidden=T|Text=445-6899-1-ND|Name=Supplier Part Number 1|ReadOnlyState=3
|RECORD=41|OwnerIndex=448|IndexInSheet=17|OwnerPartId=-1|Location.X=1060|Location.Y=700|Color=8388608|FontID=8|Text=0.1UF|Name=VALUE
|RECORD=2|OwnerIndex=448|OwnerPartId=1|FormalType=1|Electrical=4|PinConglomerate=32|PinLength=10|Location.X=1060|Location.Y=700|Name=2|Designator=2|SwapIdPin=2|SwapIDPart=1|PinPropagationDelay=0.000000E+000
|RECORD=2|OwnerIndex=448|OwnerPartId=1|FormalType=1|Electrical=4|PinConglomerate=34|PinLength=10|Location.X=1050|Location.Y=700|Name=1|Designator=1|SwapIdPin=1|SwapIDPart=1|PinPropagationDelay=0.000000E+000
|RECORD=13|OwnerIndex=448|IsNotAccesible=T|IndexInSheet=20|OwnerPartId=1|Location.X=1057|Location.X_Frac=50000|Location.Y=700|Corner.X=1060|Corner.Y=700|LineWidth=1|Color=16711680
|RECORD=13|OwnerIndex=448|IsNotAccesible=T|IndexInSheet=21|OwnerPartId=1|Location.X=1050|Location.Y=700|Corner.X=1052|Corner.X_Frac=50000|Corner.Y=700|LineWidth=1|Color=16711680
|RECORD=13|OwnerIndex=448|IsNotAccesible=T|IndexInSheet=22|OwnerPartId=1|Location.X=1057|Location.X_Frac=50000|Location.Y=705|Corner.X=1057|Corner.X_Frac=50000|Corner.Y=695|LineWidth=1|Color=16711680
|RECORD=13|OwnerIndex=448|IsNotAccesible=T|IndexInSheet=23|OwnerPartId=1|Location.X=1052|Location.X_Frac=50000|Location.Y=705|Corner.X=1052|Corner.X_Frac=50000|Corner.Y=695|LineWidth=1|Color=16711680
|RECORD=41|OwnerIndex=448|IndexInSheet=24|OwnerPartId=-1|Location.X=1038|Location.Y=706|Color=8388608|FontID=1|IsHidden=T|Text=<VALENTIUM>|Name=VALENTIUM PART NUM
|RECORD=34|OwnerIndex=448|IndexInSheet=-1|OwnerPartId=-1|Location.X=1030|Location.Y=700|Color=8388608|FontID=1|Text=C50|Name=Designator|ReadOnlyState=1
|RECORD=41|OwnerIndex=448|IndexInSheet=-1|OwnerPartId=-1|Location.X=1038|Location.Y=706|Color=8388608|FontID=1|IsHidden=T|Text=CAP_0402_0.1UF_50V|Name=Comment|ReadOnlyState=1
|RECORD=44|OwnerIndex=448
|RECORD=45|OwnerIndex=478|IndexInSheet=-1|Description=Chip Capacitor, 0402, 2-Leads, Body 1.00x0.50mm, IPC Medium Density|UseComponentLibrary=T|ModelName=CAPC1005X06N|ModelType=PCBLIB|DatafileCount=1|ModelDatafileEntity0=CAPC1005X06N|ModelDatafileKind0=PCBLib|IsCurrent=T|DatalinksLocked=T|DatabaseDatalinksLocked=T|IntegratedModel=T|DatabaseModel=T
|RECORD=46|OwnerIndex=479
|RECORD=48|OwnerIndex=479
|RECORD=1|LibReference=PCIex4|ComponentDescription=PCIE x4 Edge Connector,OrCAD Symbol,NC|PartCount=2|DisplayModeCount=1|IndexInSheet=46|OwnerPartId=-1|Location.X=770|Location.Y=960|CurrentPartId=1|LibraryPath=*|SourceLibraryName=Connectors.IntLib|TargetFileName=*|AreaColor=11599871|Color=128|PartIDLocked=T|DesignItemId=PCIex4|AllPinCount=64
|RECORD=41|OwnerIndex=482|OwnerPartId=1|Location.X=90|Location.Y=150|Color=8388608|FontID=1|IsHidden=T|Text=NC|Name=NOTE|NotAutoPosition=T
|RECORD=41|OwnerIndex=482|IndexInSheet=1|OwnerPartId=1|Location.X=90|Location.Y=150|Color=8388608|FontID=1|IsHidden=T|Text=451|Name=Part Number|NotAutoPosition=T
|RECORD=41|OwnerIndex=482|IndexInSheet=2|OwnerPartId=1|Location.X=90|Location.Y=150|Color=8388608|FontID=1|IsHidden=T|Text=NA|Name=Manufacturer|NotAutoPosition=T
|RECORD=41|OwnerIndex=482|IndexInSheet=3|OwnerPartId=1|Location.X=90|Location.Y=150|Color=8388608|FontID=1|IsHidden=T|Text=NA|Name=Vendor P/N|NotAutoPosition=T
|RECORD=41|OwnerIndex=482|IndexInSheet=4|OwnerPartId=1|Location.X=90|Location.Y=150|Color=8388608|FontID=1|IsHidden=T|Text=SMT|Name=Part Type|NotAutoPosition=T
|RECORD=4|OwnerIndex=482|IsNotAccesible=T|IndexInSheet=5|OwnerPartId=1|Location.X=774|Location.Y=837|Color=8388608|FontID=10|Text=KEY
|RECORD=4|OwnerIndex=482|IsNotAccesible=T|IndexInSheet=6|OwnerPartId=1|Location.X=890|Location.Y=838|Color=8388608|FontID=10|Text=KEY
|RECORD=14|OwnerIndex=482|IsNotAccesible=T|IndexInSheet=7|OwnerPartId=1|Location.X=770|Location.Y=620|Corner.X=910|Corner.Y=960|LineWidth=1|Color=128|AreaColor=11599871|IsSolid=T|Transparent=T
|RECORD=2|OwnerIndex=482|OwnerPartId=1|FormalType=1|Electrical=7|PinConglomerate=58|PinLength=10|Location.X=770|Location.Y=950|Name=+12v1|Designator=B1|SwapIDPart=Ž&Ž||PinPropagationDelay=0.000000E+000
|RECORD=2|OwnerIndex=482|OwnerPartId=1|FormalType=1|Electrical=7|PinConglomerate=58|PinLength=10|Location.X=770|Location.Y=940|Name=+12V2|Designator=B2|SwapIDPart=Ž&Ž||PinPropagationDelay=0.000000E+000
|RECORD=2|OwnerIndex=482|OwnerPartId=1|FormalType=1|Electrical=7|PinConglomerate=58|PinLength=10|Location.X=770|Location.Y=930|Name=+12V3|Designator=B3|SwapIDPart=Ž&Ž||PinPropagationDelay=0.000000E+000
|RECORD=2|OwnerIndex=482|OwnerPartId=1|FormalType=1|Electrical=7|PinConglomerate=58|PinLength=10|Location.X=770|Location.Y=920|Name=GND1|Designator=B4|SwapIDPart=Ž&Ž||PinPropagationDelay=0.000000E+000
|RECORD=2|OwnerIndex=482|OwnerPartId=1|FormalType=1|Electrical=4|PinConglomerate=58|PinLength=10|Location.X=770|Location.Y=910|Name=SMCLK|Designator=B5|SwapIDPart=Ž&Ž||PinPropagationDelay=0.000000E+000
|RECORD=2|OwnerIndex=482|OwnerPartId=1|FormalType=1|Electrical=4|PinConglomerate=58|PinLength=10|Location.X=770|Location.Y=900|Name=SMDATA|Designator=B6|SwapIDPart=Ž&Ž||PinPropagationDelay=0.000000E+000
|RECORD=2|OwnerIndex=482|OwnerPartId=1|FormalType=1|Electrical=7|PinConglomerate=58|PinLength=10|Location.X=770|Location.Y=890|Name=GND2|Designator=B7|SwapIDPart=Ž&Ž||PinPropagationDelay=0.000000E+000
|RECORD=2|OwnerIndex=482|OwnerPartId=1|FormalType=1|Electrical=7|PinConglomerate=58|PinLength=10|Location.X=770|Location.Y=880|Name=+3.3V1|Designator=B8|SwapIDPart=Ž&Ž||PinPropagationDelay=0.000000E+000
|RECORD=2|OwnerIndex=482|OwnerPartId=1|FormalType=1|Electrical=4|PinConglomerate=58|PinLength=10|Location.X=770|Location.Y=870|Name=JTAG/TRST_n|Designator=B9|SwapIDPart=Ž&Ž||PinPropagationDelay=0.000000E+000
|RECORD=2|OwnerIndex=482|OwnerPartId=1|FormalType=1|Electrical=4|PinConglomerate=58|PinLength=10|Location.X=770|Location.Y=860|Name=+3.3vaux|Designator=B10|SwapIDPart=Ž&Ž||PinPropagationDelay=0.000000E+000
|RECORD=2|OwnerIndex=482|OwnerPartId=1|FormalType=1|Electrical=4|PinConglomerate=58|PinLength=10|Location.X=770|Location.Y=850|Name=WAKE_n|Designator=B11|SwapIDPart=Ž&Ž||PinPropagationDelay=0.000000E+000
|RECORD=2|OwnerIndex=482|OwnerPartId=1|FormalType=1|Electrical=4|PinConglomerate=58|PinLength=10|Location.X=770|Location.Y=830|Name=RESERVED1|Designator=B12|SwapIDPart=Ž&Ž||PinPropagationDelay=0.000000E+000
|RECORD=2|OwnerIndex=482|OwnerPartId=1|FormalType=1|Electrical=7|PinConglomerate=58|PinLength=10|Location.X=770|Location.Y=820|Name=GND3|Designator=B13|SwapIDPart=Ž&Ž||PinPropagationDelay=0.000000E+000
|RECORD=2|OwnerIndex=482|OwnerPartId=1|FormalType=1|Electrical=4|PinConglomerate=58|PinLength=10|Location.X=770|Location.Y=810|Name=PETp0|Designator=B14|SwapIDPart=Ž&Ž||PinPropagationDelay=0.000000E+000
|RECORD=2|OwnerIndex=482|OwnerPartId=1|FormalType=1|Electrical=4|PinConglomerate=58|PinLength=10|Location.X=770|Location.Y=800|Name=PETn0|Designator=B15|SwapIDPart=Ž&Ž||PinPropagationDelay=0.000000E+000
|RECORD=2|OwnerIndex=482|OwnerPartId=1|FormalType=1|Electrical=7|PinConglomerate=58|PinLength=10|Location.X=770|Location.Y=790|Name=GND4|Designator=B16|SwapIDPart=Ž&Ž||PinPropagationDelay=0.000000E+000
|RECORD=2|OwnerIndex=482|OwnerPartId=1|FormalType=1|Electrical=4|PinConglomerate=58|PinLength=10|Location.X=770|Location.Y=780|Name=PRSNT2_n|Designator=B17|SwapIDPart=Ž&Ž||PinPropagationDelay=0.000000E+000
|RECORD=2|OwnerIndex=482|OwnerPartId=1|FormalType=1|Electrical=7|PinConglomerate=58|PinLength=10|Location.X=770|Location.Y=770|Name=GND5|Designator=B18|SwapIDPart=Ž&Ž||PinPropagationDelay=0.000000E+000
|RECORD=2|OwnerIndex=482|OwnerPartId=1|FormalType=1|Electrical=4|PinConglomerate=58|PinLength=10|Location.X=770|Location.Y=760|Name=PETp1|Designator=B19|SwapIDPart=Ž&Ž||PinPropagationDelay=0.000000E+000
|RECORD=2|OwnerIndex=482|OwnerPartId=1|FormalType=1|Electrical=4|PinConglomerate=58|PinLength=10|Location.X=770|Location.Y=750|Name=PETn1|Designator=B20|SwapIDPart=Ž&Ž||PinPropagationDelay=0.000000E+000
|RECORD=2|OwnerIndex=482|OwnerPartId=1|FormalType=1|Electrical=7|PinConglomerate=58|PinLength=10|Location.X=770|Location.Y=740|Name=GND6|Designator=B21|SwapIDPart=Ž&Ž||PinPropagationDelay=0.000000E+000
|RECORD=2|OwnerIndex=482|OwnerPartId=1|FormalType=1|Electrical=7|PinConglomerate=58|PinLength=10|Location.X=770|Location.Y=730|Name=GND7|Designator=B22|SwapIDPart=Ž&Ž||PinPropagationDelay=0.000000E+000
|RECORD=2|OwnerIndex=482|OwnerPartId=1|FormalType=1|Electrical=4|PinConglomerate=58|PinLength=10|Location.X=770|Location.Y=720|Name=PETp2|Designator=B23|SwapIDPart=Ž&Ž||PinPropagationDelay=0.000000E+000
|RECORD=2|OwnerIndex=482|OwnerPartId=1|FormalType=1|Electrical=4|PinConglomerate=58|PinLength=10|Location.X=770|Location.Y=710|Name=PETn2|Designator=B24|SwapIDPart=Ž&Ž||PinPropagationDelay=0.000000E+000
|RECORD=2|OwnerIndex=482|OwnerPartId=1|FormalType=1|Electrical=7|PinConglomerate=58|PinLength=10|Location.X=770|Location.Y=700|Name=GND8|Designator=B25|SwapIDPart=Ž&Ž||PinPropagationDelay=0.000000E+000
|RECORD=2|OwnerIndex=482|OwnerPartId=1|FormalType=1|Electrical=7|PinConglomerate=58|PinLength=10|Location.X=770|Location.Y=690|Name=GND9|Designator=B26|SwapIDPart=Ž&Ž||PinPropagationDelay=0.000000E+000
|RECORD=2|OwnerIndex=482|OwnerPartId=1|FormalType=1|Electrical=4|PinConglomerate=58|PinLength=10|Location.X=770|Location.Y=680|Name=PETp3|Designator=B27|SwapIDPart=Ž&Ž||PinPropagationDelay=0.000000E+000
|RECORD=2|OwnerIndex=482|OwnerPartId=1|FormalType=1|Electrical=4|PinConglomerate=58|PinLength=10|Location.X=770|Location.Y=670|Name=PETn3|Designator=B28|SwapIDPart=Ž&Ž||PinPropagationDelay=0.000000E+000
|RECORD=2|OwnerIndex=482|OwnerPartId=1|FormalType=1|Electrical=7|PinConglomerate=58|PinLength=10|Location.X=770|Location.Y=660|Name=GND10|Designator=B29|SwapIDPart=Ž&Ž||PinPropagationDelay=0.000000E+000
|RECORD=2|OwnerIndex=482|OwnerPartId=1|FormalType=1|Electrical=4|PinConglomerate=58|PinLength=10|Location.X=770|Location.Y=650|Name=RESERVED2|Designator=B30|SwapIDPart=Ž&Ž||PinPropagationDelay=0.000000E+000
|RECORD=2|OwnerIndex=482|OwnerPartId=1|FormalType=1|Electrical=4|PinConglomerate=58|PinLength=10|Location.X=770|Location.Y=640|Name=PRSNT4_n|Designator=B31|SwapIDPart=Ž&Ž||PinPropagationDelay=0.000000E+000
|RECORD=2|OwnerIndex=482|OwnerPartId=1|FormalType=1|Electrical=7|PinConglomerate=58|PinLength=10|Location.X=770|Location.Y=630|Name=GND11|Designator=B32|SwapIDPart=Ž&Ž||PinPropagationDelay=0.000000E+000
|RECORD=2|OwnerIndex=482|OwnerPartId=1|FormalType=1|Electrical=4|PinConglomerate=56|PinLength=10|Location.X=910|Location.Y=950|Name=PRSNT1_n|Designator=A1|SwapIDPart=Ž&Ž||PinPropagationDelay=0.000000E+000
|RECORD=2|OwnerIndex=482|OwnerPartId=1|FormalType=1|Electrical=4|PinConglomerate=56|PinLength=10|Location.X=910|Location.Y=940|Name=+12V5|Designator=A2|SwapIDPart=Ž&Ž||PinPropagationDelay=0.000000E+000
|RECORD=2|OwnerIndex=482|OwnerPartId=1|FormalType=1|Electrical=4|PinConglomerate=56|PinLength=10|Location.X=910|Location.Y=930|Name=+12V4|Designator=A3|SwapIDPart=Ž&Ž||PinPropagationDelay=0.000000E+000
|RECORD=2|OwnerIndex=482|OwnerPartId=1|FormalType=1|Electrical=7|PinConglomerate=56|PinLength=10|Location.X=910|Location.Y=920|Name=GND37|Designator=A4|SwapIDPart=Ž&Ž||PinPropagationDelay=0.000000E+000
|RECORD=2|OwnerIndex=482|OwnerPartId=1|FormalType=1|Electrical=4|PinConglomerate=56|PinLength=10|Location.X=910|Location.Y=910|Name=JTAG/TCK|Designator=A5|SwapIDPart=Ž&Ž||PinPropagationDelay=0.000000E+000
|RECORD=2|OwnerIndex=482|OwnerPartId=1|FormalType=1|Electrical=4|PinConglomerate=56|PinLength=10|Location.X=910|Location.Y=900|Name=JTAG/TDI|Designator=A6|SwapIDPart=Ž&Ž||PinPropagationDelay=0.000000E+000
|RECORD=2|OwnerIndex=482|OwnerPartId=1|FormalType=1|Electrical=4|PinConglomerate=56|PinLength=10|Location.X=910|Location.Y=890|Name=JTAG/TDO|Designator=A7|SwapIDPart=Ž&Ž||PinPropagationDelay=0.000000E+000
|RECORD=2|OwnerIndex=482|OwnerPartId=1|FormalType=1|Electrical=4|PinConglomerate=56|PinLength=10|Location.X=910|Location.Y=880|Name=JTAG/TMS|Designator=A8|SwapIDPart=Ž&Ž||PinPropagationDelay=0.000000E+000
|RECORD=2|OwnerIndex=482|OwnerPartId=1|FormalType=1|Electrical=4|PinConglomerate=56|PinLength=10|Location.X=910|Location.Y=870|Name=+3.3V3|Designator=A9|SwapIDPart=Ž&Ž||PinPropagationDelay=0.000000E+000
|RECORD=2|OwnerIndex=482|OwnerPartId=1|FormalType=1|Electrical=4|PinConglomerate=56|PinLength=10|Location.X=910|Location.Y=860|Name=+3.3V2|Designator=A10|SwapIDPart=Ž&Ž||PinPropagationDelay=0.000000E+000
|RECORD=2|OwnerIndex=482|OwnerPartId=1|FormalType=1|Electrical=4|PinConglomerate=56|PinLength=10|Location.X=910|Location.Y=850|Name=PERST|Designator=A11|SwapIDPart=Ž&Ž||PinPropagationDelay=0.000000E+000
|RECORD=2|OwnerIndex=482|OwnerPartId=1|FormalType=1|Electrical=7|PinConglomerate=56|PinLength=10|Location.X=910|Location.Y=830|Name=GND36|Designator=A12|SwapIDPart=Ž&Ž||PinPropagationDelay=0.000000E+000
|RECORD=2|OwnerIndex=482|OwnerPartId=1|FormalType=1|Electrical=4|PinConglomerate=56|PinLength=10|Location.X=910|Location.Y=820|Name=REFCLK+|Designator=A13|SwapIDPart=Ž&Ž||PinPropagationDelay=0.000000E+000
|RECORD=2|OwnerIndex=482|OwnerPartId=1|FormalType=1|Electrical=4|PinConglomerate=56|PinLength=10|Location.X=910|Location.Y=810|Name=REFCLK-|Designator=A14|SwapIDPart=Ž&Ž||PinPropagationDelay=0.000000E+000
|RECORD=2|OwnerIndex=482|OwnerPartId=1|FormalType=1|Electrical=7|PinConglomerate=56|PinLength=10|Location.X=910|Location.Y=800|Name=GND35|Designator=A15|SwapIDPart=Ž&Ž||PinPropagationDelay=0.000000E+000
|RECORD=2|OwnerIndex=482|OwnerPartId=1|FormalType=1|Electrical=4|PinConglomerate=56|PinLength=10|Location.X=910|Location.Y=790|Name=PERp0|Designator=A16|SwapIDPart=Ž&Ž||PinPropagationDelay=0.000000E+000
|RECORD=2|OwnerIndex=482|OwnerPartId=1|FormalType=1|Electrical=4|PinConglomerate=56|PinLength=10|Location.X=910|Location.Y=780|Name=PERn0|Designator=A17|SwapIDPart=Ž&Ž||PinPropagationDelay=0.000000E+000
|RECORD=2|OwnerIndex=482|OwnerPartId=1|FormalType=1|Electrical=7|PinConglomerate=56|PinLength=10|Location.X=910|Location.Y=770|Name=GND34|Designator=A18|SwapIDPart=Ž&Ž||PinPropagationDelay=0.000000E+000
|RECORD=2|OwnerIndex=482|OwnerPartId=1|FormalType=1|Electrical=4|PinConglomerate=56|PinLength=10|Location.X=910|Location.Y=760|Name=RESERVED5|Designator=A19|SwapIDPart=Ž&Ž||PinPropagationDelay=0.000000E+000
|RECORD=2|OwnerIndex=482|OwnerPartId=1|FormalType=1|Electrical=7|PinConglomerate=56|PinLength=10|Location.X=910|Location.Y=750|Name=GND33|Designator=A20|SwapIDPart=Ž&Ž||PinPropagationDelay=0.000000E+000
|RECORD=2|OwnerIndex=482|OwnerPartId=1|FormalType=1|Electrical=4|PinConglomerate=56|PinLength=10|Location.X=910|Location.Y=740|Name=PERp1|Designator=A21|SwapIDPart=Ž&Ž||PinPropagationDelay=0.000000E+000
|RECORD=2|OwnerIndex=482|OwnerPartId=1|FormalType=1|Electrical=4|PinConglomerate=56|PinLength=10|Location.X=910|Location.Y=730|Name=PERn1|Designator=A22|SwapIDPart=Ž&Ž||PinPropagationDelay=0.000000E+000
|RECORD=2|OwnerIndex=482|OwnerPartId=1|FormalType=1|Electrical=7|PinConglomerate=56|PinLength=10|Location.X=910|Location.Y=720|Name=GND32|Designator=A23|SwapIDPart=Ž&Ž||PinPropagationDelay=0.000000E+000
|RECORD=2|OwnerIndex=482|OwnerPartId=1|FormalType=1|Electrical=7|PinConglomerate=56|PinLength=10|Location.X=910|Location.Y=710|Name=GND31|Designator=A24|SwapIDPart=Ž&Ž||PinPropagationDelay=0.000000E+000
|RECORD=2|OwnerIndex=482|OwnerPartId=1|FormalType=1|Electrical=4|PinConglomerate=56|PinLength=10|Location.X=910|Location.Y=700|Name=PERp2|Designator=A25|SwapIDPart=Ž&Ž||PinPropagationDelay=0.000000E+000
|RECORD=2|OwnerIndex=482|OwnerPartId=1|FormalType=1|Electrical=4|PinConglomerate=56|PinLength=10|Location.X=910|Location.Y=690|Name=PERn2|Designator=A26|SwapIDPart=Ž&Ž||PinPropagationDelay=0.000000E+000
|RECORD=2|OwnerIndex=482|OwnerPartId=1|FormalType=1|Electrical=7|PinConglomerate=56|PinLength=10|Location.X=910|Location.Y=680|Name=GND30|Designator=A27|SwapIDPart=Ž&Ž||PinPropagationDelay=0.000000E+000
|RECORD=2|OwnerIndex=482|OwnerPartId=1|FormalType=1|Electrical=7|PinConglomerate=56|PinLength=10|Location.X=910|Location.Y=670|Name=GND29|Designator=A28|SwapIDPart=Ž&Ž||PinPropagationDelay=0.000000E+000
|RECORD=2|OwnerIndex=482|OwnerPartId=1|FormalType=1|Electrical=4|PinConglomerate=56|PinLength=10|Location.X=910|Location.Y=660|Name=PERp3|Designator=A29|SwapIDPart=Ž&Ž||PinPropagationDelay=0.000000E+000
|RECORD=2|OwnerIndex=482|OwnerPartId=1|FormalType=1|Electrical=4|PinConglomerate=56|PinLength=10|Location.X=910|Location.Y=650|Name=PERn3|Designator=A30|SwapIDPart=Ž&Ž||PinPropagationDelay=0.000000E+000
|RECORD=2|OwnerIndex=482|OwnerPartId=1|FormalType=1|Electrical=7|PinConglomerate=56|PinLength=10|Location.X=910|Location.Y=640|Name=GND28|Designator=A31|SwapIDPart=Ž&Ž||PinPropagationDelay=0.000000E+000
|RECORD=2|OwnerIndex=482|OwnerPartId=1|FormalType=1|Electrical=4|PinConglomerate=56|PinLength=10|Location.X=910|Location.Y=630|Name=RESERVED4|Designator=A32|SwapIDPart=Ž&Ž||PinPropagationDelay=0.000000E+000
|RECORD=34|OwnerIndex=482|IndexInSheet=-1|OwnerPartId=1|Location.X=770|Location.Y=963|Color=8388608|FontID=9|Text=P2|Name=Designator|ReadOnlyState=1|OverrideNotAutoPosition=T
|RECORD=41|OwnerIndex=482|IndexInSheet=-1|OwnerPartId=-1|Location.X=882|Location.Y=609|Color=8388608|FontID=1|Text=PCIex4|Name=Comment|NotAutoPosition=T
|RECORD=44|OwnerIndex=482
|RECORD=45|OwnerIndex=621|IndexInSheet=-1|Description=PCIE_4LANE_EDGE|UseComponentLibrary=T|ModelName=PCIE_4LANE_EDGE|ModelType=PCBLIB|DatafileCount=1|ModelDatafileEntity0=PCIE_4LANE_EDGE|ModelDatafileKind0=PCBLib|IsCurrent=T|DatalinksLocked=T|DatabaseDatalinksLocked=T|IntegratedModel=T|DatabaseModel=T
|RECORD=46|OwnerIndex=622
|RECORD=48|OwnerIndex=622
|RECORD=45|OwnerIndex=621|IndexInSheet=-1|ModelName=ALINX_FPGA|ModelType=PCBLIB|DatafileCount=1|ModelDatafileEntity0=ALINX_FPGA|ModelDatafileKind0=PCBLib|IntegratedModel=T|DatabaseModel=T
|RECORD=46|OwnerIndex=625
|RECORD=48|OwnerIndex=625
|RECORD=17|IndexInSheet=47|OwnerPartId=-1|Style=4|ShowNetName=T|Location.X=1010|Location.Y=330|Orientation=3|Color=128|FontID=1|Text=GND
|RECORD=17|IndexInSheet=48|OwnerPartId=-1|ShowNetName=T|Location.X=1030|Location.Y=410|Orientation=1|Color=128|FontID=1|Text=+3.3V
|RECORD=17|IndexInSheet=49|OwnerPartId=-1|Style=4|ShowNetName=T|Location.X=590|Location.Y=180|Orientation=3|Color=128|FontID=1|Text=GND
|RECORD=17|IndexInSheet=50|OwnerPartId=-1|Style=4|ShowNetName=T|Location.X=730|Location.Y=180|Orientation=3|Color=128|FontID=1|Text=GND
|RECORD=17|IndexInSheet=51|OwnerPartId=-1|Style=4|ShowNetName=T|Location.X=870|Location.Y=180|Orientation=3|Color=128|FontID=1|Text=GND
|RECORD=17|IndexInSheet=52|OwnerPartId=-1|Style=4|ShowNetName=T|Location.X=1010|Location.Y=180|Orientation=3|Color=128|FontID=1|Text=GND
|RECORD=17|IndexInSheet=53|OwnerPartId=-1|ShowNetName=T|Location.X=630|Location.Y=170|Orientation=3|Color=128|FontID=1|Text=+3.3V
|RECORD=17|IndexInSheet=54|OwnerPartId=-1|ShowNetName=T|Location.X=770|Location.Y=169|Orientation=3|Color=128|FontID=1|Text=+3.3V
|RECORD=17|IndexInSheet=55|OwnerPartId=-1|ShowNetName=T|Location.X=910|Location.Y=170|Orientation=3|Color=128|FontID=1|Text=+3.3V
|RECORD=17|IndexInSheet=56|OwnerPartId=-1|ShowNetName=T|Location.X=1050|Location.Y=170|Orientation=3|Color=128|FontID=1|Text=+3.3V
|RECORD=17|IndexInSheet=57|OwnerPartId=-1|ShowNetName=T|Location.X=730|Location.Y=430|Orientation=2|Color=255|FontID=1|Text=FPGA_TCK|IsCrossSheetConnector=T
|RECORD=17|IndexInSheet=58|OwnerPartId=-1|ShowNetName=T|Location.X=730|Location.Y=400|Orientation=2|Color=255|FontID=1|Text=FPGA_TDO|IsCrossSheetConnector=T
|RECORD=17|IndexInSheet=59|OwnerPartId=-1|ShowNetName=T|Location.X=730|Location.Y=370|Orientation=2|Color=255|FontID=1|Text=FPGA_TMS|IsCrossSheetConnector=T
|RECORD=17|IndexInSheet=60|OwnerPartId=-1|ShowNetName=T|Location.X=730|Location.Y=340|Orientation=2|Color=255|FontID=1|Text=FPGA_TDI|IsCrossSheetConnector=T
|RECORD=4|IndexInSheet=61|OwnerPartId=-1|Location.X=910|Location.Y=430|Color=8388608|FontID=7|Text=JTAG
|RECORD=1|LibReference=RES_0805_33|ComponentDescription=RES, 33 OHM, 1%, 1/8W, TF, 0805|PartCount=2|DisplayModeCount=1|IndexInSheet=62|OwnerPartId=-1|Location.X=790|Location.Y=430|CurrentPartId=1|LibraryPath=*|SourceLibraryName=Resistors.IntLib|TargetFileName=*|AreaColor=11599871|Color=128|PartIDLocked=F|DesignItemId=RES_0805_33|AllPinCount=2
|RECORD=41|OwnerIndex=643|OwnerPartId=-1|Location.X=790|Location.Y=430|Color=8388608|FontID=8|IsHidden=T|Text=CRCW080533R0FKEA|Name=MFG PART NUM
|RECORD=41|OwnerIndex=643|IndexInSheet=1|OwnerPartId=-1|Location.X=790|Location.Y=430|Color=8388608|FontID=8|IsHidden=T|Text=VISHAY/DALE|Name=MFG NAME
|RECORD=41|OwnerIndex=643|IndexInSheet=2|OwnerPartId=-1|Location.X=790|Location.Y=430|Color=8388608|FontID=8|IsHidden=T|Text=RES|Name=CATEGORY
|RECORD=41|OwnerIndex=643|IndexInSheet=3|OwnerPartId=-1|Location.X=790|Location.Y=430|Color=8388608|FontID=8|IsHidden=T|Text=7/26/2013|Name=ModifyDate
|RECORD=41|OwnerIndex=643|IndexInSheet=4|OwnerPartId=-1|Location.X=788|Location.Y=440|Color=8388608|FontID=8|IsHidden=T|Name=Date
|RECORD=41|OwnerIndex=643|IndexInSheet=5|OwnerPartId=-1|Location.X=778|Location.X_Frac=55769|Location.Y=440|Color=8388608|FontID=8|IsHidden=T|Text=1%|Name=P1
|RECORD=41|OwnerIndex=643|IndexInSheet=6|OwnerPartId=-1|Location.X=778|Location.X_Frac=55769|Location.Y=440|Color=8388608|FontID=8|IsHidden=T|Text=TF|Name=P3
|RECORD=41|OwnerIndex=643|IndexInSheet=7|OwnerPartId=-1|Location.X=778|Location.X_Frac=55769|Location.Y=440|Color=8388608|FontID=8|IsHidden=T|Text=1/8W|Name=P2
|RECORD=41|OwnerIndex=643|IndexInSheet=8|OwnerPartId=-1|Location.X=778|Location.X_Frac=55769|Location.Y=440|Color=8388608|FontID=8|IsHidden=T|Text=125C|Name=MAXTEMP
|RECORD=41|OwnerIndex=643|IndexInSheet=9|OwnerPartId=-1|Location.X=778|Location.X_Frac=55769|Location.Y=440|Color=8388608|FontID=8|IsHidden=T|Text=-55C|Name=MINTEMP
|RECORD=41|OwnerIndex=643|IndexInSheet=10|OwnerPartId=-1|Location.X=778|Location.X_Frac=55769|Location.Y=440|Color=8388608|FontID=8|IsHidden=T|Text=100PPM|Name=OTHER
|RECORD=41|OwnerIndex=643|IndexInSheet=11|OwnerPartId=-1|Location.X=778|Location.X_Frac=55769|Location.Y=440|Color=8388608|FontID=8|IsHidden=T|Text=0805|Name=SIZE
|RECORD=41|OwnerIndex=643|IndexInSheet=12|OwnerPartId=-1|Location.X=778|Location.X_Frac=55769|Location.Y=440|Color=8388608|FontID=8|IsHidden=T|Name=SUB
|RECORD=41|OwnerIndex=643|IndexInSheet=13|OwnerPartId=-1|Location.X=778|Location.X_Frac=55769|Location.Y=440|Color=8388608|FontID=8|IsHidden=T|Text=Digi-Key|Name=Supplier 1|ReadOnlyState=3
|RECORD=41|OwnerIndex=643|IndexInSheet=14|OwnerPartId=-1|Location.X=778|Location.X_Frac=55769|Location.Y=440|Color=8388608|FontID=8|IsHidden=T|Text=541-33.0CCT-ND|Name=Supplier Part Number 1|ReadOnlyState=3
|RECORD=41|OwnerIndex=643|IndexInSheet=15|OwnerPartId=-1|Location.X=773|Location.X_Frac=98077|Location.Y=416|Color=8388608|FontID=1|IsHidden=T|Text=*|Name=SHEETPART
|RECORD=41|OwnerIndex=643|IndexInSheet=16|OwnerPartId=-1|Location.X=773|Location.X_Frac=98077|Location.Y=444|Color=8388608|FontID=1|IsHidden=T|Text=RES, 33 OHM, 1%, 1/8W, TF, 0805|Name=DESC
|RECORD=41|OwnerIndex=643|IndexInSheet=17|OwnerPartId=-1|Location.X=799|Location.Y=414|Color=8388608|FontID=8|Text=33 OHM|Name=VALUE
|RECORD=2|OwnerIndex=643|OwnerPartId=1|FormalType=1|Electrical=4|PinConglomerate=34|PinLength=10|Location.X=800|Location.Y=430|Name=1|Designator=1|PinPropagationDelay=0.000000E+000
|RECORD=2|OwnerIndex=643|OwnerPartId=1|FormalType=1|Electrical=4|PinConglomerate=32|PinLength=10|Location.X=830|Location.Y=430|Name=2|Designator=2|PinPropagationDelay=0.000000E+000
|RECORD=6|OwnerIndex=643|IsNotAccesible=T|IndexInSheet=20|OwnerPartId=1|LineWidth=1|Color=16711680|LocationCount=7|X1=830|Y1=430|X2=827|Y2=433|X3=821|Y3=427|X4=815|Y4=433|X5=809|Y5=427|X6=803|Y6=433|X7=800|Y7=430
|RECORD=41|OwnerIndex=643|IndexInSheet=21|OwnerPartId=-1|Location.X=774|Location.X_Frac=61102|Location.Y=444|Color=8388608|FontID=1|IsHidden=T|Text=<VELENTIUM>|Name=VELENTIUM PART NUM
|RECORD=34|OwnerIndex=643|IndexInSheet=-1|OwnerPartId=-1|Location.X=799|Location.Y=434|Color=8388608|FontID=1|Text=R18|Name=Designator|ReadOnlyState=1
|RECORD=41|OwnerIndex=643|IndexInSheet=-1|OwnerPartId=-1|Location.X=810|Location.Y=420|Color=8388608|FontID=1|IsHidden=T|Text==MFG PART NUM|Name=Comment
|RECORD=44|OwnerIndex=643
|RECORD=45|OwnerIndex=670|IndexInSheet=-1|Description=Chip Resistor, 0805, 2-Leads, Body 2.05x1.25mm, IPC Medium Density|UseComponentLibrary=T|ModelName=RESC2012X50N|ModelType=PCBLIB|DatafileCount=1|ModelDatafileEntity0=RESC2012X50N|ModelDatafileKind0=PCBLib|IsCurrent=T|DatalinksLocked=T|DatabaseDatalinksLocked=T|IntegratedModel=T|DatabaseModel=T
|RECORD=46|OwnerIndex=671
|RECORD=48|OwnerIndex=671
|RECORD=1|LibReference=RES_0805_33|ComponentDescription=RES, 33 OHM, 1%, 1/8W, TF, 0805|PartCount=2|DisplayModeCount=1|IndexInSheet=63|OwnerPartId=-1|Location.X=790|Location.Y=400|CurrentPartId=1|LibraryPath=*|SourceLibraryName=Resistors.IntLib|TargetFileName=*|AreaColor=11599871|Color=128|PartIDLocked=F|DesignItemId=RES_0805_33|AllPinCount=2
|RECORD=41|OwnerIndex=674|OwnerPartId=-1|Location.X=790|Location.Y=400|Color=8388608|FontID=8|IsHidden=T|Text=CRCW080533R0FKEA|Name=MFG PART NUM
|RECORD=41|OwnerIndex=674|IndexInSheet=1|OwnerPartId=-1|Location.X=790|Location.Y=400|Color=8388608|FontID=8|IsHidden=T|Text=VISHAY/DALE|Name=MFG NAME
|RECORD=41|OwnerIndex=674|IndexInSheet=2|OwnerPartId=-1|Location.X=790|Location.Y=400|Color=8388608|FontID=8|IsHidden=T|Text=RES|Name=CATEGORY
|RECORD=41|OwnerIndex=674|IndexInSheet=3|OwnerPartId=-1|Location.X=790|Location.Y=400|Color=8388608|FontID=8|IsHidden=T|Text=7/26/2013|Name=ModifyDate
|RECORD=41|OwnerIndex=674|IndexInSheet=4|OwnerPartId=-1|Location.X=788|Location.Y=410|Color=8388608|FontID=8|IsHidden=T|Name=Date
|RECORD=41|OwnerIndex=674|IndexInSheet=5|OwnerPartId=-1|Location.X=778|Location.X_Frac=55769|Location.Y=410|Color=8388608|FontID=8|IsHidden=T|Text=1%|Name=P1
|RECORD=41|OwnerIndex=674|IndexInSheet=6|OwnerPartId=-1|Location.X=778|Location.X_Frac=55769|Location.Y=410|Color=8388608|FontID=8|IsHidden=T|Text=TF|Name=P3
|RECORD=41|OwnerIndex=674|IndexInSheet=7|OwnerPartId=-1|Location.X=778|Location.X_Frac=55769|Location.Y=410|Color=8388608|FontID=8|IsHidden=T|Text=1/8W|Name=P2
|RECORD=41|OwnerIndex=674|IndexInSheet=8|OwnerPartId=-1|Location.X=778|Location.X_Frac=55769|Location.Y=410|Color=8388608|FontID=8|IsHidden=T|Text=125C|Name=MAXTEMP
|RECORD=41|OwnerIndex=674|IndexInSheet=9|OwnerPartId=-1|Location.X=778|Location.X_Frac=55769|Location.Y=410|Color=8388608|FontID=8|IsHidden=T|Text=-55C|Name=MINTEMP
|RECORD=41|OwnerIndex=674|IndexInSheet=10|OwnerPartId=-1|Location.X=778|Location.X_Frac=55769|Location.Y=410|Color=8388608|FontID=8|IsHidden=T|Text=100PPM|Name=OTHER
|RECORD=41|OwnerIndex=674|IndexInSheet=11|OwnerPartId=-1|Location.X=778|Location.X_Frac=55769|Location.Y=410|Color=8388608|FontID=8|IsHidden=T|Text=0805|Name=SIZE
|RECORD=41|OwnerIndex=674|IndexInSheet=12|OwnerPartId=-1|Location.X=778|Location.X_Frac=55769|Location.Y=410|Color=8388608|FontID=8|IsHidden=T|Name=SUB
|RECORD=41|OwnerIndex=674|IndexInSheet=13|OwnerPartId=-1|Location.X=778|Location.X_Frac=55769|Location.Y=410|Color=8388608|FontID=8|IsHidden=T|Text=Digi-Key|Name=Supplier 1|ReadOnlyState=3
|RECORD=41|OwnerIndex=674|IndexInSheet=14|OwnerPartId=-1|Location.X=778|Location.X_Frac=55769|Location.Y=410|Color=8388608|FontID=8|IsHidden=T|Text=541-33.0CCT-ND|Name=Supplier Part Number 1|ReadOnlyState=3
|RECORD=41|OwnerIndex=674|IndexInSheet=15|OwnerPartId=-1|Location.X=773|Location.X_Frac=98077|Location.Y=386|Color=8388608|FontID=1|IsHidden=T|Text=*|Name=SHEETPART
|RECORD=41|OwnerIndex=674|IndexInSheet=16|OwnerPartId=-1|Location.X=773|Location.X_Frac=98077|Location.Y=414|Color=8388608|FontID=1|IsHidden=T|Text=RES, 33 OHM, 1%, 1/8W, TF, 0805|Name=DESC
|RECORD=41|OwnerIndex=674|IndexInSheet=17|OwnerPartId=-1|Location.X=799|Location.Y=384|Color=8388608|FontID=8|Text=33 OHM|Name=VALUE
|RECORD=2|OwnerIndex=674|OwnerPartId=1|FormalType=1|Electrical=4|PinConglomerate=34|PinLength=10|Location.X=800|Location.Y=400|Name=1|Designator=1|PinPropagationDelay=0.000000E+000
|RECORD=2|OwnerIndex=674|OwnerPartId=1|FormalType=1|Electrical=4|PinConglomerate=32|PinLength=10|Location.X=830|Location.Y=400|Name=2|Designator=2|PinPropagationDelay=0.000000E+000
|RECORD=6|OwnerIndex=674|IsNotAccesible=T|IndexInSheet=20|OwnerPartId=1|LineWidth=1|Color=16711680|LocationCount=7|X1=830|Y1=400|X2=827|Y2=403|X3=821|Y3=397|X4=815|Y4=403|X5=809|Y5=397|X6=803|Y6=403|X7=800|Y7=400
|RECORD=41|OwnerIndex=674|IndexInSheet=21|OwnerPartId=-1|Location.X=774|Location.X_Frac=61102|Location.Y=414|Color=8388608|FontID=1|IsHidden=T|Text=<VELENTIUM>|Name=VELENTIUM PART NUM
|RECORD=34|OwnerIndex=674|IndexInSheet=-1|OwnerPartId=-1|Location.X=799|Location.Y=404|Color=8388608|FontID=1|Text=R19|Name=Designator|ReadOnlyState=1
|RECORD=41|OwnerIndex=674|IndexInSheet=-1|OwnerPartId=-1|Location.X=810|Location.Y=390|Color=8388608|FontID=1|IsHidden=T|Text==MFG PART NUM|Name=Comment
|RECORD=44|OwnerIndex=674
|RECORD=45|OwnerIndex=701|IndexInSheet=-1|Description=Chip Resistor, 0805, 2-Leads, Body 2.05x1.25mm, IPC Medium Density|UseComponentLibrary=T|ModelName=RESC2012X50N|ModelType=PCBLIB|DatafileCount=1|ModelDatafileEntity0=RESC2012X50N|ModelDatafileKind0=PCBLib|IsCurrent=T|DatalinksLocked=T|DatabaseDatalinksLocked=T|IntegratedModel=T|DatabaseModel=T
|RECORD=46|OwnerIndex=702
|RECORD=48|OwnerIndex=702
|RECORD=1|LibReference=RES_0805_33|ComponentDescription=RES, 33 OHM, 1%, 1/8W, TF, 0805|PartCount=2|DisplayModeCount=1|IndexInSheet=64|OwnerPartId=-1|Location.X=790|Location.Y=370|CurrentPartId=1|LibraryPath=*|SourceLibraryName=Resistors.IntLib|TargetFileName=*|AreaColor=11599871|Color=128|PartIDLocked=F|DesignItemId=RES_0805_33|AllPinCount=2
|RECORD=41|OwnerIndex=705|OwnerPartId=-1|Location.X=790|Location.Y=370|Color=8388608|FontID=8|IsHidden=T|Text=CRCW080533R0FKEA|Name=MFG PART NUM
|RECORD=41|OwnerIndex=705|IndexInSheet=1|OwnerPartId=-1|Location.X=790|Location.Y=370|Color=8388608|FontID=8|IsHidden=T|Text=VISHAY/DALE|Name=MFG NAME
|RECORD=41|OwnerIndex=705|IndexInSheet=2|OwnerPartId=-1|Location.X=790|Location.Y=370|Color=8388608|FontID=8|IsHidden=T|Text=RES|Name=CATEGORY
|RECORD=41|OwnerIndex=705|IndexInSheet=3|OwnerPartId=-1|Location.X=790|Location.Y=370|Color=8388608|FontID=8|IsHidden=T|Text=7/26/2013|Name=ModifyDate
|RECORD=41|OwnerIndex=705|IndexInSheet=4|OwnerPartId=-1|Location.X=788|Location.Y=380|Color=8388608|FontID=8|IsHidden=T|Name=Date
|RECORD=41|OwnerIndex=705|IndexInSheet=5|OwnerPartId=-1|Location.X=778|Location.X_Frac=55769|Location.Y=380|Color=8388608|FontID=8|IsHidden=T|Text=1%|Name=P1
|RECORD=41|OwnerIndex=705|IndexInSheet=6|OwnerPartId=-1|Location.X=778|Location.X_Frac=55769|Location.Y=380|Color=8388608|FontID=8|IsHidden=T|Text=TF|Name=P3
|RECORD=41|OwnerIndex=705|IndexInSheet=7|OwnerPartId=-1|Location.X=778|Location.X_Frac=55769|Location.Y=380|Color=8388608|FontID=8|IsHidden=T|Text=1/8W|Name=P2
|RECORD=41|OwnerIndex=705|IndexInSheet=8|OwnerPartId=-1|Location.X=778|Location.X_Frac=55769|Location.Y=380|Color=8388608|FontID=8|IsHidden=T|Text=125C|Name=MAXTEMP
|RECORD=41|OwnerIndex=705|IndexInSheet=9|OwnerPartId=-1|Location.X=778|Location.X_Frac=55769|Location.Y=380|Color=8388608|FontID=8|IsHidden=T|Text=-55C|Name=MINTEMP
|RECORD=41|OwnerIndex=705|IndexInSheet=10|OwnerPartId=-1|Location.X=778|Location.X_Frac=55769|Location.Y=380|Color=8388608|FontID=8|IsHidden=T|Text=100PPM|Name=OTHER
|RECORD=41|OwnerIndex=705|IndexInSheet=11|OwnerPartId=-1|Location.X=778|Location.X_Frac=55769|Location.Y=380|Color=8388608|FontID=8|IsHidden=T|Text=0805|Name=SIZE
|RECORD=41|OwnerIndex=705|IndexInSheet=12|OwnerPartId=-1|Location.X=778|Location.X_Frac=55769|Location.Y=380|Color=8388608|FontID=8|IsHidden=T|Name=SUB
|RECORD=41|OwnerIndex=705|IndexInSheet=13|OwnerPartId=-1|Location.X=778|Location.X_Frac=55769|Location.Y=380|Color=8388608|FontID=8|IsHidden=T|Text=Digi-Key|Name=Supplier 1|ReadOnlyState=3
|RECORD=41|OwnerIndex=705|IndexInSheet=14|OwnerPartId=-1|Location.X=778|Location.X_Frac=55769|Location.Y=380|Color=8388608|FontID=8|IsHidden=T|Text=541-33.0CCT-ND|Name=Supplier Part Number 1|ReadOnlyState=3
|RECORD=41|OwnerIndex=705|IndexInSheet=15|OwnerPartId=-1|Location.X=773|Location.X_Frac=98077|Location.Y=356|Color=8388608|FontID=1|IsHidden=T|Text=*|Name=SHEETPART
|RECORD=41|OwnerIndex=705|IndexInSheet=16|OwnerPartId=-1|Location.X=773|Location.X_Frac=98077|Location.Y=384|Color=8388608|FontID=1|IsHidden=T|Text=RES, 33 OHM, 1%, 1/8W, TF, 0805|Name=DESC
|RECORD=41|OwnerIndex=705|IndexInSheet=17|OwnerPartId=-1|Location.X=799|Location.Y=354|Color=8388608|FontID=8|Text=33 OHM|Name=VALUE
|RECORD=2|OwnerIndex=705|OwnerPartId=1|FormalType=1|Electrical=4|PinConglomerate=34|PinLength=10|Location.X=800|Location.Y=370|Name=1|Designator=1|PinPropagationDelay=0.000000E+000
|RECORD=2|OwnerIndex=705|OwnerPartId=1|FormalType=1|Electrical=4|PinConglomerate=32|PinLength=10|Location.X=830|Location.Y=370|Name=2|Designator=2|PinPropagationDelay=0.000000E+000
|RECORD=6|OwnerIndex=705|IsNotAccesible=T|IndexInSheet=20|OwnerPartId=1|LineWidth=1|Color=16711680|LocationCount=7|X1=830|Y1=370|X2=827|Y2=373|X3=821|Y3=367|X4=815|Y4=373|X5=809|Y5=367|X6=803|Y6=373|X7=800|Y7=370
|RECORD=41|OwnerIndex=705|IndexInSheet=21|OwnerPartId=-1|Location.X=774|Location.X_Frac=61102|Location.Y=384|Color=8388608|FontID=1|IsHidden=T|Text=<VELENTIUM>|Name=VELENTIUM PART NUM
|RECORD=34|OwnerIndex=705|IndexInSheet=-1|OwnerPartId=-1|Location.X=799|Location.Y=374|Color=8388608|FontID=1|Text=R20|Name=Designator|ReadOnlyState=1
|RECORD=41|OwnerIndex=705|IndexInSheet=-1|OwnerPartId=-1|Location.X=810|Location.Y=360|Color=8388608|FontID=1|IsHidden=T|Text==MFG PART NUM|Name=Comment
|RECORD=44|OwnerIndex=705
|RECORD=45|OwnerIndex=732|IndexInSheet=-1|Description=Chip Resistor, 0805, 2-Leads, Body 2.05x1.25mm, IPC Medium Density|UseComponentLibrary=T|ModelName=RESC2012X50N|ModelType=PCBLIB|DatafileCount=1|ModelDatafileEntity0=RESC2012X50N|ModelDatafileKind0=PCBLib|IsCurrent=T|DatalinksLocked=T|DatabaseDatalinksLocked=T|IntegratedModel=T|DatabaseModel=T
|RECORD=46|OwnerIndex=733
|RECORD=48|OwnerIndex=733
|RECORD=1|LibReference=RES_0805_33|ComponentDescription=RES, 33 OHM, 1%, 1/8W, TF, 0805|PartCount=2|DisplayModeCount=1|IndexInSheet=65|OwnerPartId=-1|Location.X=790|Location.Y=340|CurrentPartId=1|LibraryPath=*|SourceLibraryName=Resistors.IntLib|TargetFileName=*|AreaColor=11599871|Color=128|PartIDLocked=F|DesignItemId=RES_0805_33|AllPinCount=2
|RECORD=41|OwnerIndex=736|OwnerPartId=-1|Location.X=790|Location.Y=340|Color=8388608|FontID=8|IsHidden=T|Text=CRCW080533R0FKEA|Name=MFG PART NUM
|RECORD=41|OwnerIndex=736|IndexInSheet=1|OwnerPartId=-1|Location.X=790|Location.Y=340|Color=8388608|FontID=8|IsHidden=T|Text=VISHAY/DALE|Name=MFG NAME
|RECORD=41|OwnerIndex=736|IndexInSheet=2|OwnerPartId=-1|Location.X=790|Location.Y=340|Color=8388608|FontID=8|IsHidden=T|Text=RES|Name=CATEGORY
|RECORD=41|OwnerIndex=736|IndexInSheet=3|OwnerPartId=-1|Location.X=790|Location.Y=340|Color=8388608|FontID=8|IsHidden=T|Text=7/26/2013|Name=ModifyDate
|RECORD=41|OwnerIndex=736|IndexInSheet=4|OwnerPartId=-1|Location.X=788|Location.Y=350|Color=8388608|FontID=8|IsHidden=T|Name=Date
|RECORD=41|OwnerIndex=736|IndexInSheet=5|OwnerPartId=-1|Location.X=778|Location.X_Frac=55769|Location.Y=350|Color=8388608|FontID=8|IsHidden=T|Text=1%|Name=P1
|RECORD=41|OwnerIndex=736|IndexInSheet=6|OwnerPartId=-1|Location.X=778|Location.X_Frac=55769|Location.Y=350|Color=8388608|FontID=8|IsHidden=T|Text=TF|Name=P3
|RECORD=41|OwnerIndex=736|IndexInSheet=7|OwnerPartId=-1|Location.X=778|Location.X_Frac=55769|Location.Y=350|Color=8388608|FontID=8|IsHidden=T|Text=1/8W|Name=P2
|RECORD=41|OwnerIndex=736|IndexInSheet=8|OwnerPartId=-1|Location.X=778|Location.X_Frac=55769|Location.Y=350|Color=8388608|FontID=8|IsHidden=T|Text=125C|Name=MAXTEMP
|RECORD=41|OwnerIndex=736|IndexInSheet=9|OwnerPartId=-1|Location.X=778|Location.X_Frac=55769|Location.Y=350|Color=8388608|FontID=8|IsHidden=T|Text=-55C|Name=MINTEMP
|RECORD=41|OwnerIndex=736|IndexInSheet=10|OwnerPartId=-1|Location.X=778|Location.X_Frac=55769|Location.Y=350|Color=8388608|FontID=8|IsHidden=T|Text=100PPM|Name=OTHER
|RECORD=41|OwnerIndex=736|IndexInSheet=11|OwnerPartId=-1|Location.X=778|Location.X_Frac=55769|Location.Y=350|Color=8388608|FontID=8|IsHidden=T|Text=0805|Name=SIZE
|RECORD=41|OwnerIndex=736|IndexInSheet=12|OwnerPartId=-1|Location.X=778|Location.X_Frac=55769|Location.Y=350|Color=8388608|FontID=8|IsHidden=T|Name=SUB
|RECORD=41|OwnerIndex=736|IndexInSheet=13|OwnerPartId=-1|Location.X=778|Location.X_Frac=55769|Location.Y=350|Color=8388608|FontID=8|IsHidden=T|Text=Digi-Key|Name=Supplier 1|ReadOnlyState=3
|RECORD=41|OwnerIndex=736|IndexInSheet=14|OwnerPartId=-1|Location.X=778|Location.X_Frac=55769|Location.Y=350|Color=8388608|FontID=8|IsHidden=T|Text=541-33.0CCT-ND|Name=Supplier Part Number 1|ReadOnlyState=3
|RECORD=41|OwnerIndex=736|IndexInSheet=15|OwnerPartId=-1|Location.X=773|Location.X_Frac=98077|Location.Y=326|Color=8388608|FontID=1|IsHidden=T|Text=*|Name=SHEETPART
|RECORD=41|OwnerIndex=736|IndexInSheet=16|OwnerPartId=-1|Location.X=773|Location.X_Frac=98077|Location.Y=354|Color=8388608|FontID=1|IsHidden=T|Text=RES, 33 OHM, 1%, 1/8W, TF, 0805|Name=DESC
|RECORD=41|OwnerIndex=736|IndexInSheet=17|OwnerPartId=-1|Location.X=799|Location.Y=324|Color=8388608|FontID=8|Text=33 OHM|Name=VALUE
|RECORD=2|OwnerIndex=736|OwnerPartId=1|FormalType=1|Electrical=4|PinConglomerate=34|PinLength=10|Location.X=800|Location.Y=340|Name=1|Designator=1|PinPropagationDelay=0.000000E+000
|RECORD=2|OwnerIndex=736|OwnerPartId=1|FormalType=1|Electrical=4|PinConglomerate=32|PinLength=10|Location.X=830|Location.Y=340|Name=2|Designator=2|PinPropagationDelay=0.000000E+000
|RECORD=6|OwnerIndex=736|IsNotAccesible=T|IndexInSheet=20|OwnerPartId=1|LineWidth=1|Color=16711680|LocationCount=7|X1=830|Y1=340|X2=827|Y2=343|X3=821|Y3=337|X4=815|Y4=343|X5=809|Y5=337|X6=803|Y6=343|X7=800|Y7=340
|RECORD=41|OwnerIndex=736|IndexInSheet=21|OwnerPartId=-1|Location.X=774|Location.X_Frac=61102|Location.Y=354|Color=8388608|FontID=1|IsHidden=T|Text=<VELENTIUM>|Name=VELENTIUM PART NUM
|RECORD=34|OwnerIndex=736|IndexInSheet=-1|OwnerPartId=-1|Location.X=799|Location.Y=344|Color=8388608|FontID=1|Text=R21|Name=Designator|ReadOnlyState=1
|RECORD=41|OwnerIndex=736|IndexInSheet=-1|OwnerPartId=-1|Location.X=810|Location.Y=330|Color=8388608|FontID=1|IsHidden=T|Text==MFG PART NUM|Name=Comment
|RECORD=44|OwnerIndex=736
|RECORD=45|OwnerIndex=763|IndexInSheet=-1|Description=Chip Resistor, 0805, 2-Leads, Body 2.05x1.25mm, IPC Medium Density|UseComponentLibrary=T|ModelName=RESC2012X50N|ModelType=PCBLIB|DatafileCount=1|ModelDatafileEntity0=RESC2012X50N|ModelDatafileKind0=PCBLib|IsCurrent=T|DatalinksLocked=T|DatabaseDatalinksLocked=T|IntegratedModel=T|DatabaseModel=T
|RECORD=46|OwnerIndex=764
|RECORD=48|OwnerIndex=764
|RECORD=1|LibReference=BAT54SW|ComponentDescription=DIO, SCHOTTKY, BAT54S, DUAL SERIES, 30V, 200MA, SC-70|PartCount=2|DisplayModeCount=1|IndexInSheet=66|OwnerPartId=-1|Location.X=1020|Location.Y=180|Orientation=1|CurrentPartId=1|LibraryPath=*|SourceLibraryName=Passives.IntLib|TargetFileName=*|AreaColor=11599871|Color=128|PartIDLocked=F|DesignItemId=BAT54SW|AllPinCount=3
|RECORD=41|OwnerIndex=767|OwnerPartId=-1|Location.X=1009|Location.Y=252|Color=8388608|FontID=8|IsHidden=T|Text=BAT54SWQ-7-F|Name=MFG PART NUM
|RECORD=41|OwnerIndex=767|IndexInSheet=1|OwnerPartId=-1|Location.X=1009|Location.Y=252|Color=8388608|FontID=8|IsHidden=T|Text=9/4/2013|Name=MODIFY DATE
|RECORD=41|OwnerIndex=767|IndexInSheet=2|OwnerPartId=-1|Location.X=1009|Location.Y=252|Color=8388608|FontID=8|IsHidden=T|Text=DIODES INC|Name=MFG NAME
|RECORD=41|OwnerIndex=767|IndexInSheet=3|OwnerPartId=-1|Location.X=1009|Location.Y=252|Color=8388608|FontID=8|IsHidden=T|Text=DIO, SCHOTTKY|Name=CATEGORY
|RECORD=41|OwnerIndex=767|IndexInSheet=4|OwnerPartId=-1|Location.X=1009|Location.Y=252|Color=8388608|FontID=8|IsHidden=T|Name=DATE
|RECORD=41|OwnerIndex=767|IndexInSheet=5|OwnerPartId=-1|Location.X=1009|Location.Y=252|Color=8388608|FontID=8|IsHidden=T|Text=150C|Name=MAXTEMP
|RECORD=41|OwnerIndex=767|IndexInSheet=6|OwnerPartId=-1|Location.X=1009|Location.Y=252|Color=8388608|FontID=8|IsHidden=T|Text=-55C|Name=MINTEMP
|RECORD=41|OwnerIndex=767|IndexInSheet=7|OwnerPartId=-1|Location.X=1009|Location.Y=252|Color=8388608|FontID=8|IsHidden=T|Text=SERIES|Name=OTHER
|RECORD=41|OwnerIndex=767|IndexInSheet=8|OwnerPartId=-1|Location.X=1009|Location.Y=252|Color=8388608|FontID=8|IsHidden=T|Text=SCHOTTKY|Name=P1
|RECORD=41|OwnerIndex=767|IndexInSheet=9|OwnerPartId=-1|Location.X=1009|Location.Y=252|Color=8388608|FontID=8|IsHidden=T|Text=30V|Name=P2
|RECORD=41|OwnerIndex=767|IndexInSheet=10|OwnerPartId=-1|Location.X=1009|Location.Y=252|Color=8388608|FontID=8|IsHidden=T|Text=200mA,200mW|Name=P3
|RECORD=41|OwnerIndex=767|IndexInSheet=11|OwnerPartId=-1|Location.X=1009|Location.Y=252|Color=8388608|FontID=8|IsHidden=T|Text=SC-70|Name=SIZE
|RECORD=41|OwnerIndex=767|IndexInSheet=12|OwnerPartId=-1|Location.X=1009|Location.Y=252|Color=8388608|FontID=8|IsHidden=T|Name=SUB
|RECORD=41|OwnerIndex=767|IndexInSheet=13|OwnerPartId=-1|Location.X=1009|Location.Y=252|Color=8388608|FontID=1|IsHidden=T|Text=*|Name=SHEETPART
|RECORD=41|OwnerIndex=767|IndexInSheet=14|OwnerPartId=-1|Location.X=1009|Location.Y=252|Color=8388608|FontID=1|IsHidden=T|Text=DIO, SCHOTTKY, BAT54S, DUAL SERIES, 30V, 200MA, SC-70|Name=DESC
|RECORD=41|OwnerIndex=767|IndexInSheet=15|OwnerPartId=-1|Location.X=1009|Location.Y=252|Color=8388608|FontID=1|IsHidden=T|Text=Digi-Key|Name=Supplier 1|ReadOnlyState=3
|RECORD=41|OwnerIndex=767|IndexInSheet=16|OwnerPartId=-1|Location.X=1009|Location.Y=252|Color=8388608|FontID=1|IsHidden=T|Text=BAT54SWQ-7-FDICT-ND|Name=Supplier Part Number 1|ReadOnlyState=3
|RECORD=41|OwnerIndex=767|IndexInSheet=17|OwnerPartId=-1|Location.X=1051|Location.Y=205|Color=8388608|FontID=8|Text=BAT54SW|Name=VALUE
|RECORD=2|OwnerIndex=767|OwnerPartId=1|FormalType=1|Electrical=4|PinConglomerate=51|PinLength=20|Location.X=1040|Location.Y=200|Name=2|Designator=2|SwapIdPin=1|SwapIDPart=1|PinPropagationDelay=0.000000E+000
|RECORD=2|OwnerIndex=767|OwnerPartId=1|FormalType=1|Electrical=4|PinConglomerate=49|PinLength=20|Location.X=1030|Location.Y=230|Name=3|Designator=3|SwapIdPin=2|SwapIDPart=1|PinPropagationDelay=0.000000E+000
|RECORD=2|OwnerIndex=767|OwnerPartId=1|FormalType=1|Electrical=4|PinConglomerate=51|PinLength=20|Location.X=1020|Location.Y=200|Name=1|Designator=1|SwapIdPin=3|SwapIDPart=1|PinPropagationDelay=0.000000E+000
|RECORD=13|OwnerIndex=767|IsNotAccesible=T|IndexInSheet=21|OwnerPartId=1|Location.X=1020|Location.Y=230|Corner.X=1020|Corner.Y=220|LineWidth=1|Color=16711680
|RECORD=13|OwnerIndex=767|IsNotAccesible=T|IndexInSheet=22|OwnerPartId=1|Location.X=1030|Location.Y=208|Corner.X=1050|Corner.Y=208|LineWidth=1|Color=16711680
|RECORD=13|OwnerIndex=767|IsNotAccesible=T|IndexInSheet=23|OwnerPartId=1|Location.X=1040|Location.Y=210|Corner.X=1040|Corner.Y=200|LineWidth=1|Color=16711680
|RECORD=13|OwnerIndex=767|IsNotAccesible=T|IndexInSheet=24|OwnerPartId=1|Location.X=1040|Location.Y=230|Corner.X=1040|Corner.Y=220|LineWidth=1|Color=16711680
|RECORD=13|OwnerIndex=767|IsNotAccesible=T|IndexInSheet=25|OwnerPartId=1|Location.X=1020|Location.Y=210|Corner.X=1020|Corner.Y=200|LineWidth=1|Color=16711680
|RECORD=13|OwnerIndex=767|IsNotAccesible=T|IndexInSheet=26|OwnerPartId=1|Location.X=1010|Location.Y=220|Corner.X=1030|Corner.Y=220|LineWidth=1|Color=16711680
|RECORD=7|OwnerIndex=767|IsNotAccesible=T|IndexInSheet=27|OwnerPartId=1|LineWidth=1|Color=16711680|AreaColor=16711680|IsSolid=T|LocationCount=3|X1=1020|Y1=220|Y1_Frac=20000|X2=1012|X2_Frac=50000|Y2=207|Y2_Frac=70000|X3=1027|X3_Frac=50000|Y3=207|Y3_Frac=70000
|RECORD=7|OwnerIndex=767|IsNotAccesible=T|IndexInSheet=28|OwnerPartId=1|LineWidth=1|Color=16711680|AreaColor=16711680|IsSolid=T|LocationCount=3|X1=1040|Y1=208|X2=1047|X2_Frac=50000|Y2=220|Y2_Frac=50000|X3=1032|X3_Frac=50000|Y3=220|Y3_Frac=50000
|RECORD=6|OwnerIndex=767|IsNotAccesible=T|IndexInSheet=29|OwnerPartId=1|LineWidth=1|Color=16711680|LocationCount=2|X1=1020|Y1=230|X2=1040|Y2=230
|RECORD=41|OwnerIndex=767|IndexInSheet=30|OwnerPartId=-1|Location.X=1009|Location.Y=252|Color=8388608|FontID=1|IsHidden=T|Text=<VALENTIUM>|Name=VALENTIUM PART NUM
|RECORD=34|OwnerIndex=767|IndexInSheet=-1|OwnerPartId=-1|Location.X=1051|Location.Y=217|Color=8388608|FontID=1|Text=D8|Name=Designator|ReadOnlyState=1
|RECORD=41|OwnerIndex=767|IndexInSheet=-1|OwnerPartId=-1|Location.X=1009|Location.Y=252|Color=8388608|FontID=1|IsHidden=T|Text=BAT54SW|Name=Comment
|RECORD=44|OwnerIndex=767
|RECORD=45|OwnerIndex=804|IndexInSheet=-1|Description=SOT323-3 (SC70), 3-Leads, Body 2.00x2.10mm, Pitch 0.65mm, IPC Medium Density|UseComponentLibrary=T|ModelName=SOT65P210X110-3N|ModelType=PCBLIB|DatafileCount=1|ModelDatafileEntity0=SOT65P210X110-3N|ModelDatafileKind0=PCBLib|IsCurrent=T|DatalinksLocked=T|DatabaseDatalinksLocked=T|IntegratedModel=T|DatabaseModel=T
|RECORD=46|OwnerIndex=805
|RECORD=48|OwnerIndex=805
|RECORD=1|LibReference=BAT54SW|ComponentDescription=DIO, SCHOTTKY, BAT54S, DUAL SERIES, 30V, 200MA, SC-70|PartCount=2|DisplayModeCount=1|IndexInSheet=67|OwnerPartId=-1|Location.X=880|Location.Y=180|Orientation=1|CurrentPartId=1|LibraryPath=*|SourceLibraryName=Passives.IntLib|TargetFileName=*|AreaColor=11599871|Color=128|PartIDLocked=F|DesignItemId=BAT54SW|AllPinCount=3
|RECORD=41|OwnerIndex=808|OwnerPartId=-1|Location.X=869|Location.Y=252|Color=8388608|FontID=8|IsHidden=T|Text=BAT54SWQ-7-F|Name=MFG PART NUM
|RECORD=41|OwnerIndex=808|IndexInSheet=1|OwnerPartId=-1|Location.X=869|Location.Y=252|Color=8388608|FontID=8|IsHidden=T|Text=9/4/2013|Name=MODIFY DATE
|RECORD=41|OwnerIndex=808|IndexInSheet=2|OwnerPartId=-1|Location.X=869|Location.Y=252|Color=8388608|FontID=8|IsHidden=T|Text=DIODES INC|Name=MFG NAME
|RECORD=41|OwnerIndex=808|IndexInSheet=3|OwnerPartId=-1|Location.X=869|Location.Y=252|Color=8388608|FontID=8|IsHidden=T|Text=DIO, SCHOTTKY|Name=CATEGORY
|RECORD=41|OwnerIndex=808|IndexInSheet=4|OwnerPartId=-1|Location.X=869|Location.Y=252|Color=8388608|FontID=8|IsHidden=T|Name=DATE
|RECORD=41|OwnerIndex=808|IndexInSheet=5|OwnerPartId=-1|Location.X=869|Location.Y=252|Color=8388608|FontID=8|IsHidden=T|Text=150C|Name=MAXTEMP
|RECORD=41|OwnerIndex=808|IndexInSheet=6|OwnerPartId=-1|Location.X=869|Location.Y=252|Color=8388608|FontID=8|IsHidden=T|Text=-55C|Name=MINTEMP
|RECORD=41|OwnerIndex=808|IndexInSheet=7|OwnerPartId=-1|Location.X=869|Location.Y=252|Color=8388608|FontID=8|IsHidden=T|Text=SERIES|Name=OTHER
|RECORD=41|OwnerIndex=808|IndexInSheet=8|OwnerPartId=-1|Location.X=869|Location.Y=252|Color=8388608|FontID=8|IsHidden=T|Text=SCHOTTKY|Name=P1
|RECORD=41|OwnerIndex=808|IndexInSheet=9|OwnerPartId=-1|Location.X=869|Location.Y=252|Color=8388608|FontID=8|IsHidden=T|Text=30V|Name=P2
|RECORD=41|OwnerIndex=808|IndexInSheet=10|OwnerPartId=-1|Location.X=869|Location.Y=252|Color=8388608|FontID=8|IsHidden=T|Text=200mA,200mW|Name=P3
|RECORD=41|OwnerIndex=808|IndexInSheet=11|OwnerPartId=-1|Location.X=869|Location.Y=252|Color=8388608|FontID=8|IsHidden=T|Text=SC-70|Name=SIZE
|RECORD=41|OwnerIndex=808|IndexInSheet=12|OwnerPartId=-1|Location.X=869|Location.Y=252|Color=8388608|FontID=8|IsHidden=T|Name=SUB
|RECORD=41|OwnerIndex=808|IndexInSheet=13|OwnerPartId=-1|Location.X=869|Location.Y=252|Color=8388608|FontID=1|IsHidden=T|Text=*|Name=SHEETPART
|RECORD=41|OwnerIndex=808|IndexInSheet=14|OwnerPartId=-1|Location.X=869|Location.Y=252|Color=8388608|FontID=1|IsHidden=T|Text=DIO, SCHOTTKY, BAT54S, DUAL SERIES, 30V, 200MA, SC-70|Name=DESC
|RECORD=41|OwnerIndex=808|IndexInSheet=15|OwnerPartId=-1|Location.X=869|Location.Y=252|Color=8388608|FontID=1|IsHidden=T|Text=Digi-Key|Name=Supplier 1|ReadOnlyState=3
|RECORD=41|OwnerIndex=808|IndexInSheet=16|OwnerPartId=-1|Location.X=869|Location.Y=252|Color=8388608|FontID=1|IsHidden=T|Text=BAT54SWQ-7-FDICT-ND|Name=Supplier Part Number 1|ReadOnlyState=3
|RECORD=41|OwnerIndex=808|IndexInSheet=17|OwnerPartId=-1|Location.X=911|Location.Y=205|Color=8388608|FontID=8|Text=BAT54SW|Name=VALUE
|RECORD=2|OwnerIndex=808|OwnerPartId=1|FormalType=1|Electrical=4|PinConglomerate=51|PinLength=20|Location.X=900|Location.Y=200|Name=2|Designator=2|SwapIdPin=1|SwapIDPart=1|PinPropagationDelay=0.000000E+000
|RECORD=2|OwnerIndex=808|OwnerPartId=1|FormalType=1|Electrical=4|PinConglomerate=49|PinLength=20|Location.X=890|Location.Y=230|Name=3|Designator=3|SwapIdPin=2|SwapIDPart=1|PinPropagationDelay=0.000000E+000
|RECORD=2|OwnerIndex=808|OwnerPartId=1|FormalType=1|Electrical=4|PinConglomerate=51|PinLength=20|Location.X=880|Location.Y=200|Name=1|Designator=1|SwapIdPin=3|SwapIDPart=1|PinPropagationDelay=0.000000E+000
|RECORD=13|OwnerIndex=808|IsNotAccesible=T|IndexInSheet=21|OwnerPartId=1|Location.X=880|Location.Y=230|Corner.X=880|Corner.Y=220|LineWidth=1|Color=16711680
|RECORD=13|OwnerIndex=808|IsNotAccesible=T|IndexInSheet=22|OwnerPartId=1|Location.X=890|Location.Y=208|Corner.X=910|Corner.Y=208|LineWidth=1|Color=16711680
|RECORD=13|OwnerIndex=808|IsNotAccesible=T|IndexInSheet=23|OwnerPartId=1|Location.X=900|Location.Y=210|Corner.X=900|Corner.Y=200|LineWidth=1|Color=16711680
|RECORD=13|OwnerIndex=808|IsNotAccesible=T|IndexInSheet=24|OwnerPartId=1|Location.X=900|Location.Y=230|Corner.X=900|Corner.Y=220|LineWidth=1|Color=16711680
|RECORD=13|OwnerIndex=808|IsNotAccesible=T|IndexInSheet=25|OwnerPartId=1|Location.X=880|Location.Y=210|Corner.X=880|Corner.Y=200|LineWidth=1|Color=16711680
|RECORD=13|OwnerIndex=808|IsNotAccesible=T|IndexInSheet=26|OwnerPartId=1|Location.X=870|Location.Y=220|Corner.X=890|Corner.Y=220|LineWidth=1|Color=16711680
|RECORD=7|OwnerIndex=808|IsNotAccesible=T|IndexInSheet=27|OwnerPartId=1|LineWidth=1|Color=16711680|AreaColor=16711680|IsSolid=T|LocationCount=3|X1=880|Y1=220|Y1_Frac=20000|X2=872|X2_Frac=50000|Y2=207|Y2_Frac=70000|X3=887|X3_Frac=50000|Y3=207|Y3_Frac=70000
|RECORD=7|OwnerIndex=808|IsNotAccesible=T|IndexInSheet=28|OwnerPartId=1|LineWidth=1|Color=16711680|AreaColor=16711680|IsSolid=T|LocationCount=3|X1=900|Y1=208|X2=907|X2_Frac=50000|Y2=220|Y2_Frac=50000|X3=892|X3_Frac=50000|Y3=220|Y3_Frac=50000
|RECORD=6|OwnerIndex=808|IsNotAccesible=T|IndexInSheet=29|OwnerPartId=1|LineWidth=1|Color=16711680|LocationCount=2|X1=880|Y1=230|X2=900|Y2=230
|RECORD=41|OwnerIndex=808|IndexInSheet=30|OwnerPartId=-1|Location.X=869|Location.Y=252|Color=8388608|FontID=1|IsHidden=T|Text=<VALENTIUM>|Name=VALENTIUM PART NUM
|RECORD=34|OwnerIndex=808|IndexInSheet=-1|OwnerPartId=-1|Location.X=911|Location.Y=217|Color=8388608|FontID=1|Text=D7|Name=Designator|ReadOnlyState=1
|RECORD=41|OwnerIndex=808|IndexInSheet=-1|OwnerPartId=-1|Location.X=869|Location.Y=252|Color=8388608|FontID=1|IsHidden=T|Text=BAT54SW|Name=Comment
|RECORD=44|OwnerIndex=808
|RECORD=45|OwnerIndex=845|IndexInSheet=-1|Description=SOT323-3 (SC70), 3-Leads, Body 2.00x2.10mm, Pitch 0.65mm, IPC Medium Density|UseComponentLibrary=T|ModelName=SOT65P210X110-3N|ModelType=PCBLIB|DatafileCount=1|ModelDatafileEntity0=SOT65P210X110-3N|ModelDatafileKind0=PCBLib|IsCurrent=T|DatalinksLocked=T|DatabaseDatalinksLocked=T|IntegratedModel=T|DatabaseModel=T
|RECORD=46|OwnerIndex=846
|RECORD=48|OwnerIndex=846
|RECORD=1|LibReference=BAT54SW|ComponentDescription=DIO, SCHOTTKY, BAT54S, DUAL SERIES, 30V, 200MA, SC-70|PartCount=2|DisplayModeCount=1|IndexInSheet=68|OwnerPartId=-1|Location.X=740|Location.Y=180|Orientation=1|CurrentPartId=1|LibraryPath=*|SourceLibraryName=Passives.IntLib|TargetFileName=*|AreaColor=11599871|Color=128|PartIDLocked=F|DesignItemId=BAT54SW|AllPinCount=3
|RECORD=41|OwnerIndex=849|OwnerPartId=-1|Location.X=729|Location.Y=252|Color=8388608|FontID=8|IsHidden=T|Text=BAT54SWQ-7-F|Name=MFG PART NUM
|RECORD=41|OwnerIndex=849|IndexInSheet=1|OwnerPartId=-1|Location.X=729|Location.Y=252|Color=8388608|FontID=8|IsHidden=T|Text=9/4/2013|Name=MODIFY DATE
|RECORD=41|OwnerIndex=849|IndexInSheet=2|OwnerPartId=-1|Location.X=729|Location.Y=252|Color=8388608|FontID=8|IsHidden=T|Text=DIODES INC|Name=MFG NAME
|RECORD=41|OwnerIndex=849|IndexInSheet=3|OwnerPartId=-1|Location.X=729|Location.Y=252|Color=8388608|FontID=8|IsHidden=T|Text=DIO, SCHOTTKY|Name=CATEGORY
|RECORD=41|OwnerIndex=849|IndexInSheet=4|OwnerPartId=-1|Location.X=729|Location.Y=252|Color=8388608|FontID=8|IsHidden=T|Name=DATE
|RECORD=41|OwnerIndex=849|IndexInSheet=5|OwnerPartId=-1|Location.X=729|Location.Y=252|Color=8388608|FontID=8|IsHidden=T|Text=150C|Name=MAXTEMP
|RECORD=41|OwnerIndex=849|IndexInSheet=6|OwnerPartId=-1|Location.X=729|Location.Y=252|Color=8388608|FontID=8|IsHidden=T|Text=-55C|Name=MINTEMP
|RECORD=41|OwnerIndex=849|IndexInSheet=7|OwnerPartId=-1|Location.X=729|Location.Y=252|Color=8388608|FontID=8|IsHidden=T|Text=SERIES|Name=OTHER
|RECORD=41|OwnerIndex=849|IndexInSheet=8|OwnerPartId=-1|Location.X=729|Location.Y=252|Color=8388608|FontID=8|IsHidden=T|Text=SCHOTTKY|Name=P1
|RECORD=41|OwnerIndex=849|IndexInSheet=9|OwnerPartId=-1|Location.X=729|Location.Y=252|Color=8388608|FontID=8|IsHidden=T|Text=30V|Name=P2
|RECORD=41|OwnerIndex=849|IndexInSheet=10|OwnerPartId=-1|Location.X=729|Location.Y=252|Color=8388608|FontID=8|IsHidden=T|Text=200mA,200mW|Name=P3
|RECORD=41|OwnerIndex=849|IndexInSheet=11|OwnerPartId=-1|Location.X=729|Location.Y=252|Color=8388608|FontID=8|IsHidden=T|Text=SC-70|Name=SIZE
|RECORD=41|OwnerIndex=849|IndexInSheet=12|OwnerPartId=-1|Location.X=729|Location.Y=252|Color=8388608|FontID=8|IsHidden=T|Name=SUB
|RECORD=41|OwnerIndex=849|IndexInSheet=13|OwnerPartId=-1|Location.X=729|Location.Y=252|Color=8388608|FontID=1|IsHidden=T|Text=*|Name=SHEETPART
|RECORD=41|OwnerIndex=849|IndexInSheet=14|OwnerPartId=-1|Location.X=729|Location.Y=252|Color=8388608|FontID=1|IsHidden=T|Text=DIO, SCHOTTKY, BAT54S, DUAL SERIES, 30V, 200MA, SC-70|Name=DESC
|RECORD=41|OwnerIndex=849|IndexInSheet=15|OwnerPartId=-1|Location.X=729|Location.Y=252|Color=8388608|FontID=1|IsHidden=T|Text=Digi-Key|Name=Supplier 1|ReadOnlyState=3
|RECORD=41|OwnerIndex=849|IndexInSheet=16|OwnerPartId=-1|Location.X=729|Location.Y=252|Color=8388608|FontID=1|IsHidden=T|Text=BAT54SWQ-7-FDICT-ND|Name=Supplier Part Number 1|ReadOnlyState=3
|RECORD=41|OwnerIndex=849|IndexInSheet=17|OwnerPartId=-1|Location.X=771|Location.Y=205|Color=8388608|FontID=8|Text=BAT54SW|Name=VALUE
|RECORD=2|OwnerIndex=849|OwnerPartId=1|FormalType=1|Electrical=4|PinConglomerate=51|PinLength=20|Location.X=760|Location.Y=200|Name=2|Designator=2|SwapIdPin=1|SwapIDPart=1|PinPropagationDelay=0.000000E+000
|RECORD=2|OwnerIndex=849|OwnerPartId=1|FormalType=1|Electrical=4|PinConglomerate=49|PinLength=20|Location.X=750|Location.Y=230|Name=3|Designator=3|SwapIdPin=2|SwapIDPart=1|PinPropagationDelay=0.000000E+000
|RECORD=2|OwnerIndex=849|OwnerPartId=1|FormalType=1|Electrical=4|PinConglomerate=51|PinLength=20|Location.X=740|Location.Y=200|Name=1|Designator=1|SwapIdPin=3|SwapIDPart=1|PinPropagationDelay=0.000000E+000
|RECORD=13|OwnerIndex=849|IsNotAccesible=T|IndexInSheet=21|OwnerPartId=1|Location.X=740|Location.Y=230|Corner.X=740|Corner.Y=220|LineWidth=1|Color=16711680
|RECORD=13|OwnerIndex=849|IsNotAccesible=T|IndexInSheet=22|OwnerPartId=1|Location.X=750|Location.Y=208|Corner.X=770|Corner.Y=208|LineWidth=1|Color=16711680
|RECORD=13|OwnerIndex=849|IsNotAccesible=T|IndexInSheet=23|OwnerPartId=1|Location.X=760|Location.Y=210|Corner.X=760|Corner.Y=200|LineWidth=1|Color=16711680
|RECORD=13|OwnerIndex=849|IsNotAccesible=T|IndexInSheet=24|OwnerPartId=1|Location.X=760|Location.Y=230|Corner.X=760|Corner.Y=220|LineWidth=1|Color=16711680
|RECORD=13|OwnerIndex=849|IsNotAccesible=T|IndexInSheet=25|OwnerPartId=1|Location.X=740|Location.Y=210|Corner.X=740|Corner.Y=200|LineWidth=1|Color=16711680
|RECORD=13|OwnerIndex=849|IsNotAccesible=T|IndexInSheet=26|OwnerPartId=1|Location.X=730|Location.Y=220|Corner.X=750|Corner.Y=220|LineWidth=1|Color=16711680
|RECORD=7|OwnerIndex=849|IsNotAccesible=T|IndexInSheet=27|OwnerPartId=1|LineWidth=1|Color=16711680|AreaColor=16711680|IsSolid=T|LocationCount=3|X1=740|Y1=220|Y1_Frac=20000|X2=732|X2_Frac=50000|Y2=207|Y2_Frac=70000|X3=747|X3_Frac=50000|Y3=207|Y3_Frac=70000
|RECORD=7|OwnerIndex=849|IsNotAccesible=T|IndexInSheet=28|OwnerPartId=1|LineWidth=1|Color=16711680|AreaColor=16711680|IsSolid=T|LocationCount=3|X1=760|Y1=208|X2=767|X2_Frac=50000|Y2=220|Y2_Frac=50000|X3=752|X3_Frac=50000|Y3=220|Y3_Frac=50000
|RECORD=6|OwnerIndex=849|IsNotAccesible=T|IndexInSheet=29|OwnerPartId=1|LineWidth=1|Color=16711680|LocationCount=2|X1=740|Y1=230|X2=760|Y2=230
|RECORD=41|OwnerIndex=849|IndexInSheet=30|OwnerPartId=-1|Location.X=729|Location.Y=252|Color=8388608|FontID=1|IsHidden=T|Text=<VALENTIUM>|Name=VALENTIUM PART NUM
|RECORD=34|OwnerIndex=849|IndexInSheet=-1|OwnerPartId=-1|Location.X=771|Location.Y=217|Color=8388608|FontID=1|Text=D6|Name=Designator|ReadOnlyState=1
|RECORD=41|OwnerIndex=849|IndexInSheet=-1|OwnerPartId=-1|Location.X=729|Location.Y=252|Color=8388608|FontID=1|IsHidden=T|Text=BAT54SW|Name=Comment
|RECORD=44|OwnerIndex=849
|RECORD=45|OwnerIndex=886|IndexInSheet=-1|Description=SOT323-3 (SC70), 3-Leads, Body 2.00x2.10mm, Pitch 0.65mm, IPC Medium Density|UseComponentLibrary=T|ModelName=SOT65P210X110-3N|ModelType=PCBLIB|DatafileCount=1|ModelDatafileEntity0=SOT65P210X110-3N|ModelDatafileKind0=PCBLib|IsCurrent=T|DatalinksLocked=T|DatabaseDatalinksLocked=T|IntegratedModel=T|DatabaseModel=T
|RECORD=46|OwnerIndex=887
|RECORD=48|OwnerIndex=887
|RECORD=1|LibReference=BAT54SW|ComponentDescription=DIO, SCHOTTKY, BAT54S, DUAL SERIES, 30V, 200MA, SC-70|PartCount=2|DisplayModeCount=1|IndexInSheet=69|OwnerPartId=-1|Location.X=600|Location.Y=180|Orientation=1|CurrentPartId=1|LibraryPath=*|SourceLibraryName=Passives.IntLib|TargetFileName=*|AreaColor=11599871|Color=128|PartIDLocked=F|DesignItemId=BAT54SW|AllPinCount=3
|RECORD=41|OwnerIndex=890|OwnerPartId=-1|Location.X=589|Location.Y=252|Color=8388608|FontID=8|IsHidden=T|Text=BAT54SWQ-7-F|Name=MFG PART NUM
|RECORD=41|OwnerIndex=890|IndexInSheet=1|OwnerPartId=-1|Location.X=589|Location.Y=252|Color=8388608|FontID=8|IsHidden=T|Text=9/4/2013|Name=MODIFY DATE
|RECORD=41|OwnerIndex=890|IndexInSheet=2|OwnerPartId=-1|Location.X=589|Location.Y=252|Color=8388608|FontID=8|IsHidden=T|Text=DIODES INC|Name=MFG NAME
|RECORD=41|OwnerIndex=890|IndexInSheet=3|OwnerPartId=-1|Location.X=589|Location.Y=252|Color=8388608|FontID=8|IsHidden=T|Text=DIO, SCHOTTKY|Name=CATEGORY
|RECORD=41|OwnerIndex=890|IndexInSheet=4|OwnerPartId=-1|Location.X=589|Location.Y=252|Color=8388608|FontID=8|IsHidden=T|Name=DATE
|RECORD=41|OwnerIndex=890|IndexInSheet=5|OwnerPartId=-1|Location.X=589|Location.Y=252|Color=8388608|FontID=8|IsHidden=T|Text=150C|Name=MAXTEMP
|RECORD=41|OwnerIndex=890|IndexInSheet=6|OwnerPartId=-1|Location.X=589|Location.Y=252|Color=8388608|FontID=8|IsHidden=T|Text=-55C|Name=MINTEMP
|RECORD=41|OwnerIndex=890|IndexInSheet=7|OwnerPartId=-1|Location.X=589|Location.Y=252|Color=8388608|FontID=8|IsHidden=T|Text=SERIES|Name=OTHER
|RECORD=41|OwnerIndex=890|IndexInSheet=8|OwnerPartId=-1|Location.X=589|Location.Y=252|Color=8388608|FontID=8|IsHidden=T|Text=SCHOTTKY|Name=P1
|RECORD=41|OwnerIndex=890|IndexInSheet=9|OwnerPartId=-1|Location.X=589|Location.Y=252|Color=8388608|FontID=8|IsHidden=T|Text=30V|Name=P2
|RECORD=41|OwnerIndex=890|IndexInSheet=10|OwnerPartId=-1|Location.X=589|Location.Y=252|Color=8388608|FontID=8|IsHidden=T|Text=200mA,200mW|Name=P3
|RECORD=41|OwnerIndex=890|IndexInSheet=11|OwnerPartId=-1|Location.X=589|Location.Y=252|Color=8388608|FontID=8|IsHidden=T|Text=SC-70|Name=SIZE
|RECORD=41|OwnerIndex=890|IndexInSheet=12|OwnerPartId=-1|Location.X=589|Location.Y=252|Color=8388608|FontID=8|IsHidden=T|Name=SUB
|RECORD=41|OwnerIndex=890|IndexInSheet=13|OwnerPartId=-1|Location.X=589|Location.Y=252|Color=8388608|FontID=1|IsHidden=T|Text=*|Name=SHEETPART
|RECORD=41|OwnerIndex=890|IndexInSheet=14|OwnerPartId=-1|Location.X=589|Location.Y=252|Color=8388608|FontID=1|IsHidden=T|Text=DIO, SCHOTTKY, BAT54S, DUAL SERIES, 30V, 200MA, SC-70|Name=DESC
|RECORD=41|OwnerIndex=890|IndexInSheet=15|OwnerPartId=-1|Location.X=589|Location.Y=252|Color=8388608|FontID=1|IsHidden=T|Text=Digi-Key|Name=Supplier 1|ReadOnlyState=3
|RECORD=41|OwnerIndex=890|IndexInSheet=16|OwnerPartId=-1|Location.X=589|Location.Y=252|Color=8388608|FontID=1|IsHidden=T|Text=BAT54SWQ-7-FDICT-ND|Name=Supplier Part Number 1|ReadOnlyState=3
|RECORD=41|OwnerIndex=890|IndexInSheet=17|OwnerPartId=-1|Location.X=631|Location.Y=205|Color=8388608|FontID=8|Text=BAT54SW|Name=VALUE
|RECORD=2|OwnerIndex=890|OwnerPartId=1|FormalType=1|Electrical=4|PinConglomerate=51|PinLength=20|Location.X=620|Location.Y=200|Name=2|Designator=2|SwapIdPin=1|SwapIDPart=1|PinPropagationDelay=0.000000E+000
|RECORD=2|OwnerIndex=890|OwnerPartId=1|FormalType=1|Electrical=4|PinConglomerate=49|PinLength=20|Location.X=610|Location.Y=230|Name=3|Designator=3|SwapIdPin=2|SwapIDPart=1|PinPropagationDelay=0.000000E+000
|RECORD=2|OwnerIndex=890|OwnerPartId=1|FormalType=1|Electrical=4|PinConglomerate=51|PinLength=20|Location.X=600|Location.Y=200|Name=1|Designator=1|SwapIdPin=3|SwapIDPart=1|PinPropagationDelay=0.000000E+000
|RECORD=13|OwnerIndex=890|IsNotAccesible=T|IndexInSheet=21|OwnerPartId=1|Location.X=600|Location.Y=230|Corner.X=600|Corner.Y=220|LineWidth=1|Color=16711680
|RECORD=13|OwnerIndex=890|IsNotAccesible=T|IndexInSheet=22|OwnerPartId=1|Location.X=610|Location.Y=208|Corner.X=630|Corner.Y=208|LineWidth=1|Color=16711680
|RECORD=13|OwnerIndex=890|IsNotAccesible=T|IndexInSheet=23|OwnerPartId=1|Location.X=620|Location.Y=210|Corner.X=620|Corner.Y=200|LineWidth=1|Color=16711680
|RECORD=13|OwnerIndex=890|IsNotAccesible=T|IndexInSheet=24|OwnerPartId=1|Location.X=620|Location.Y=230|Corner.X=620|Corner.Y=220|LineWidth=1|Color=16711680
|RECORD=13|OwnerIndex=890|IsNotAccesible=T|IndexInSheet=25|OwnerPartId=1|Location.X=600|Location.Y=210|Corner.X=600|Corner.Y=200|LineWidth=1|Color=16711680
|RECORD=13|OwnerIndex=890|IsNotAccesible=T|IndexInSheet=26|OwnerPartId=1|Location.X=590|Location.Y=220|Corner.X=610|Corner.Y=220|LineWidth=1|Color=16711680
|RECORD=7|OwnerIndex=890|IsNotAccesible=T|IndexInSheet=27|OwnerPartId=1|LineWidth=1|Color=16711680|AreaColor=16711680|IsSolid=T|LocationCount=3|X1=600|Y1=220|Y1_Frac=20000|X2=592|X2_Frac=50000|Y2=207|Y2_Frac=70000|X3=607|X3_Frac=50000|Y3=207|Y3_Frac=70000
|RECORD=7|OwnerIndex=890|IsNotAccesible=T|IndexInSheet=28|OwnerPartId=1|LineWidth=1|Color=16711680|AreaColor=16711680|IsSolid=T|LocationCount=3|X1=620|Y1=208|X2=627|X2_Frac=50000|Y2=220|Y2_Frac=50000|X3=612|X3_Frac=50000|Y3=220|Y3_Frac=50000
|RECORD=6|OwnerIndex=890|IsNotAccesible=T|IndexInSheet=29|OwnerPartId=1|LineWidth=1|Color=16711680|LocationCount=2|X1=600|Y1=230|X2=620|Y2=230
|RECORD=41|OwnerIndex=890|IndexInSheet=30|OwnerPartId=-1|Location.X=589|Location.Y=252|Color=8388608|FontID=1|IsHidden=T|Text=<VALENTIUM>|Name=VALENTIUM PART NUM
|RECORD=34|OwnerIndex=890|IndexInSheet=-1|OwnerPartId=-1|Location.X=631|Location.Y=217|Color=8388608|FontID=1|Text=D5|Name=Designator|ReadOnlyState=1
|RECORD=41|OwnerIndex=890|IndexInSheet=-1|OwnerPartId=-1|Location.X=589|Location.Y=252|Color=8388608|FontID=1|IsHidden=T|Text=BAT54SW|Name=Comment
|RECORD=44|OwnerIndex=890
|RECORD=45|OwnerIndex=927|IndexInSheet=-1|Description=SOT323-3 (SC70), 3-Leads, Body 2.00x2.10mm, Pitch 0.65mm, IPC Medium Density|UseComponentLibrary=T|ModelName=SOT65P210X110-3N|ModelType=PCBLIB|DatafileCount=1|ModelDatafileEntity0=SOT65P210X110-3N|ModelDatafileKind0=PCBLib|IsCurrent=T|DatalinksLocked=T|DatabaseDatalinksLocked=T|IntegratedModel=T|DatabaseModel=T
|RECORD=46|OwnerIndex=928
|RECORD=48|OwnerIndex=928
|RECORD=25|IndexInSheet=70|OwnerPartId=-1|Location.X=940|Location.Y=950|Color=128|FontID=1|Text=PRSNT
|RECORD=25|IndexInSheet=71|OwnerPartId=-1|Location.X=600|Location.Y=780|Color=128|FontID=1|Text=PRSNT
|RECORD=25|IndexInSheet=72|OwnerPartId=-1|Location.X=600|Location.Y=640|Color=128|FontID=1|Text=PRSNT
|RECORD=17|IndexInSheet=73|OwnerPartId=-1|ShowNetName=T|Location.X=620|Location.Y=260|Color=255|FontID=1|Text=FPGA_TCK|IsCrossSheetConnector=T
|RECORD=17|IndexInSheet=74|OwnerPartId=-1|ShowNetName=T|Location.X=760|Location.Y=260|Color=255|FontID=1|Text=FPGA_TDO|IsCrossSheetConnector=T
|RECORD=17|IndexInSheet=75|OwnerPartId=-1|ShowNetName=T|Location.X=900|Location.Y=260|Color=255|FontID=1|Text=FPGA_TMS|IsCrossSheetConnector=T
|RECORD=17|IndexInSheet=76|OwnerPartId=-1|ShowNetName=T|Location.X=1040|Location.Y=260|Color=255|FontID=1|Text=FPGA_TDI|IsCrossSheetConnector=T
|RECORD=27|IndexInSheet=77|OwnerPartId=-1|LineWidth=1|Color=8388608|LocationCount=2|X1=740|Y1=690|X2=740|Y2=700
|RECORD=27|IndexInSheet=78|OwnerPartId=-1|LineWidth=1|Color=8388608|LocationCount=2|X1=760|Y1=670|X2=540|Y2=670
|RECORD=27|IndexInSheet=79|OwnerPartId=-1|LineWidth=1|Color=8388608|LocationCount=2|X1=760|Y1=680|X2=540|Y2=680
|RECORD=27|IndexInSheet=80|OwnerPartId=-1|LineWidth=1|Color=8388608|LocationCount=2|X1=760|Y1=710|X2=540|Y2=710
|RECORD=27|IndexInSheet=81|OwnerPartId=-1|LineWidth=1|Color=8388608|LocationCount=2|X1=760|Y1=720|X2=540|Y2=720
|RECORD=27|IndexInSheet=82|OwnerPartId=-1|LineWidth=1|Color=8388608|LocationCount=2|X1=760|Y1=750|X2=540|Y2=750
|RECORD=27|IndexInSheet=83|OwnerPartId=-1|LineWidth=1|Color=8388608|LocationCount=2|X1=760|Y1=760|X2=540|Y2=760
|RECORD=27|IndexInSheet=84|OwnerPartId=-1|LineWidth=1|Color=8388608|LocationCount=2|X1=760|Y1=800|X2=540|Y2=800
|RECORD=27|IndexInSheet=85|OwnerPartId=-1|LineWidth=1|Color=8388608|LocationCount=2|X1=760|Y1=810|X2=540|Y2=810
|RECORD=27|IndexInSheet=86|OwnerPartId=-1|LineWidth=1|Color=8388608|LocationCount=3|X1=760|Y1=880|X2=540|Y2=880|X3=540|Y3=970
|RECORD=27|IndexInSheet=87|OwnerPartId=-1|LineWidth=1|Color=8388608|LocationCount=2|X1=600|Y1=180|X2=590|Y2=180
|RECORD=27|IndexInSheet=88|OwnerPartId=-1|LineWidth=1|Color=8388608|LocationCount=2|X1=670|Y1=640|X2=590|Y2=640
|RECORD=27|IndexInSheet=89|OwnerPartId=-1|LineWidth=1|Color=8388608|LocationCount=2|X1=670|Y1=780|X2=590|Y2=780
|RECORD=27|IndexInSheet=90|OwnerPartId=-1|LineWidth=1|Color=8388608|LocationCount=3|X1=610|Y1=250|X2=610|Y2=260|X3=620|Y3=260
|RECORD=27|IndexInSheet=91|OwnerPartId=-1|LineWidth=1|Color=8388608|LocationCount=3|X1=630|Y1=170|X2=630|Y2=180|X3=620|Y3=180
|RECORD=27|IndexInSheet=92|OwnerPartId=-1|LineWidth=1|Color=8388608|LocationCount=5|X1=760|Y1=930|X2=670|Y2=930|X3=670|Y3=940|X4=670|Y4=950|X5=670|Y5=970
|RECORD=27|IndexInSheet=93|OwnerPartId=-1|LineWidth=1|Color=8388608|LocationCount=2|X1=760|Y1=940|X2=670|Y2=940
|RECORD=27|IndexInSheet=94|OwnerPartId=-1|LineWidth=1|Color=8388608|LocationCount=2|X1=760|Y1=950|X2=670|Y2=950
|RECORD=27|IndexInSheet=95|OwnerPartId=-1|LineWidth=1|Color=8388608|LocationCount=2|X1=760|Y1=640|X2=720|Y2=640
|RECORD=27|IndexInSheet=96|OwnerPartId=-1|LineWidth=1|Color=8388608|LocationCount=2|X1=760|Y1=780|X2=720|Y2=780
|RECORD=27|IndexInSheet=97|OwnerPartId=-1|LineWidth=1|Color=8388608|LocationCount=2|X1=740|Y1=180|X2=730|Y2=180
|RECORD=27|IndexInSheet=98|OwnerPartId=-1|LineWidth=1|Color=8388608|LocationCount=2|X1=790|Y1=340|X2=730|Y2=340
|RECORD=27|IndexInSheet=99|OwnerPartId=-1|LineWidth=1|Color=8388608|LocationCount=2|X1=790|Y1=370|X2=730|Y2=370
|RECORD=27|IndexInSheet=100|OwnerPartId=-1|LineWidth=1|Color=8388608|LocationCount=2|X1=790|Y1=400|X2=730|Y2=400
|RECORD=27|IndexInSheet=101|OwnerPartId=-1|LineWidth=1|Color=8388608|LocationCount=2|X1=790|Y1=430|X2=730|Y2=430
|RECORD=27|IndexInSheet=102|OwnerPartId=-1|LineWidth=1|Color=8388608|LocationCount=2|X1=760|Y1=630|X2=740|Y2=630
|RECORD=27|IndexInSheet=103|OwnerPartId=-1|LineWidth=1|Color=8388608|LocationCount=2|X1=760|Y1=660|X2=740|Y2=660
|RECORD=27|IndexInSheet=104|OwnerPartId=-1|LineWidth=1|Color=8388608|LocationCount=5|X1=760|Y1=690|X2=740|Y2=690|X3=740|Y3=660|X4=740|Y4=630|X5=740|Y5=600
|RECORD=27|IndexInSheet=105|OwnerPartId=-1|LineWidth=1|Color=8388608|LocationCount=2|X1=760|Y1=700|X2=740|Y2=700
|RECORD=27|IndexInSheet=106|OwnerPartId=-1|LineWidth=1|Color=8388608|LocationCount=2|X1=760|Y1=730|X2=740|Y2=730
|RECORD=27|IndexInSheet=107|OwnerPartId=-1|LineWidth=1|Color=8388608|LocationCount=2|X1=760|Y1=740|X2=740|Y2=740
|RECORD=27|IndexInSheet=108|OwnerPartId=-1|LineWidth=1|Color=8388608|LocationCount=2|X1=760|Y1=770|X2=740|Y2=770
|RECORD=27|IndexInSheet=109|OwnerPartId=-1|LineWidth=1|Color=8388608|LocationCount=2|X1=760|Y1=790|X2=740|Y2=790
|RECORD=27|IndexInSheet=110|OwnerPartId=-1|LineWidth=1|Color=8388608|LocationCount=2|X1=760|Y1=820|X2=740|Y2=820
|RECORD=27|IndexInSheet=111|OwnerPartId=-1|LineWidth=1|Color=8388608|LocationCount=2|X1=760|Y1=890|X2=740|Y2=890
|RECORD=27|IndexInSheet=112|OwnerPartId=-1|LineWidth=1|Color=8388608|LocationCount=9|X1=760|Y1=920|X2=740|Y2=920|X3=740|Y3=890|X4=740|Y4=820|X5=740|Y5=790|X6=740|Y6=770|X7=740|Y7=740|X8=740|Y8=730|X9=740|Y9=700
|RECORD=27|IndexInSheet=113|OwnerPartId=-1|LineWidth=1|Color=8388608|LocationCount=3|X1=750|Y1=250|X2=750|Y2=260|X3=760|Y3=260
|RECORD=27|IndexInSheet=114|OwnerPartId=-1|LineWidth=1|Color=8388608|LocationCount=4|X1=760|Y1=180|X2=760|Y2=179|X3=770|Y3=179|X4=770|Y4=169
|RECORD=27|IndexInSheet=115|OwnerPartId=-1|LineWidth=1|Color=8388608|LocationCount=2|X1=880|Y1=180|X2=870|Y2=180
|RECORD=27|IndexInSheet=116|OwnerPartId=-1|LineWidth=1|Color=8388608|LocationCount=3|X1=890|Y1=250|X2=890|Y2=260|X3=900|Y3=260
|RECORD=27|IndexInSheet=117|OwnerPartId=-1|LineWidth=1|Color=8388608|LocationCount=3|X1=910|Y1=170|X2=910|Y2=180|X3=900|Y3=180
|RECORD=27|IndexInSheet=118|OwnerPartId=-1|LineWidth=1|Color=8388608|LocationCount=2|X1=920|Y1=640|X2=940|Y2=640
|RECORD=27|IndexInSheet=119|OwnerPartId=-1|LineWidth=1|Color=8388608|LocationCount=2|X1=920|Y1=650|X2=1080|Y2=650
|RECORD=27|IndexInSheet=120|OwnerPartId=-1|LineWidth=1|Color=8388608|LocationCount=2|X1=920|Y1=660|X2=1040|Y2=660
|RECORD=27|IndexInSheet=121|OwnerPartId=-1|LineWidth=1|Color=8388608|LocationCount=2|X1=920|Y1=670|X2=940|Y2=670
|RECORD=27|IndexInSheet=122|OwnerPartId=-1|LineWidth=1|Color=8388608|LocationCount=2|X1=920|Y1=680|X2=940|Y2=680
|RECORD=27|IndexInSheet=123|OwnerPartId=-1|LineWidth=1|Color=8388608|LocationCount=2|X1=920|Y1=690|X2=1080|Y2=690
|RECORD=27|IndexInSheet=124|OwnerPartId=-1|LineWidth=1|Color=8388608|LocationCount=2|X1=920|Y1=700|X2=1040|Y2=700
|RECORD=27|IndexInSheet=125|OwnerPartId=-1|LineWidth=1|Color=8388608|LocationCount=2|X1=920|Y1=710|X2=940|Y2=710
|RECORD=27|IndexInSheet=126|OwnerPartId=-1|LineWidth=1|Color=8388608|LocationCount=2|X1=920|Y1=720|X2=940|Y2=720
|RECORD=27|IndexInSheet=127|OwnerPartId=-1|LineWidth=1|Color=8388608|LocationCount=2|X1=920|Y1=730|X2=1080|Y2=730
|RECORD=27|IndexInSheet=128|OwnerPartId=-1|LineWidth=1|Color=8388608|LocationCount=2|X1=920|Y1=740|X2=1040|Y2=740
|RECORD=27|IndexInSheet=129|OwnerPartId=-1|LineWidth=1|Color=8388608|LocationCount=2|X1=920|Y1=750|X2=940|Y2=750
|RECORD=27|IndexInSheet=130|OwnerPartId=-1|LineWidth=1|Color=8388608|LocationCount=2|X1=920|Y1=770|X2=940|Y2=770
|RECORD=27|IndexInSheet=131|OwnerPartId=-1|LineWidth=1|Color=8388608|LocationCount=2|X1=920|Y1=780|X2=1080|Y2=780
|RECORD=27|IndexInSheet=132|OwnerPartId=-1|LineWidth=1|Color=8388608|LocationCount=2|X1=920|Y1=790|X2=1010|Y2=790
|RECORD=27|IndexInSheet=133|OwnerPartId=-1|LineWidth=1|Color=8388608|LocationCount=2|X1=920|Y1=800|X2=940|Y2=800
|RECORD=27|IndexInSheet=134|OwnerPartId=-1|LineWidth=1|Color=8388608|LocationCount=2|X1=920|Y1=810|X2=1080|Y2=810
|RECORD=27|IndexInSheet=135|OwnerPartId=-1|LineWidth=1|Color=8388608|LocationCount=2|X1=920|Y1=820|X2=1040|Y2=820
|RECORD=27|IndexInSheet=136|OwnerPartId=-1|LineWidth=1|Color=8388608|LocationCount=2|X1=920|Y1=830|X2=940|Y2=830
|RECORD=27|IndexInSheet=137|OwnerPartId=-1|LineWidth=1|Color=8388608|LocationCount=3|X1=920|Y1=850|X2=1060|Y2=850|X3=1060|Y3=860
|RECORD=27|IndexInSheet=138|OwnerPartId=-1|LineWidth=1|Color=8388608|LocationCount=3|X1=920|Y1=860|X2=1030|Y2=860|X3=1030|Y3=870
|RECORD=27|IndexInSheet=139|OwnerPartId=-1|LineWidth=1|Color=8388608|LocationCount=3|X1=920|Y1=870|X2=1030|Y2=870|X3=1030|Y3=940
|RECORD=27|IndexInSheet=140|OwnerPartId=-1|LineWidth=1|Color=8388608|LocationCount=12|X1=920|Y1=920|X2=940|Y2=920|X3=940|Y3=830|X4=940|Y4=800|X5=940|Y5=770|X6=940|Y6=750|X7=940|Y7=720|X8=940|Y8=710|X9=940|Y9=680|X10=940|Y10=670|X11=940|Y11=640|X12=940|Y12=600
|RECORD=27|IndexInSheet=141|OwnerPartId=-1|LineWidth=1|Color=8388608|LocationCount=3|X1=920|Y1=930|X2=990|Y2=930|X3=990|Y3=940
|RECORD=27|IndexInSheet=142|OwnerPartId=-1|LineWidth=1|Color=8388608|LocationCount=3|X1=920|Y1=940|X2=990|Y2=940|X3=990|Y3=970
|RECORD=27|IndexInSheet=143|OwnerPartId=-1|LineWidth=1|Color=8388608|LocationCount=2|X1=920|Y1=950|X2=980|Y2=950
|RECORD=27|IndexInSheet=144|OwnerPartId=-1|LineWidth=1|Color=8388608|LocationCount=2|X1=1010|Y1=180|X2=1020|Y2=180
|RECORD=27|IndexInSheet=145|OwnerPartId=-1|LineWidth=1|Color=8388608|LocationCount=3|X1=1030|Y1=250|X2=1030|Y2=260|X3=1040|Y3=260
|RECORD=27|IndexInSheet=146|OwnerPartId=-1|LineWidth=1|Color=8388608|LocationCount=3|X1=1040|Y1=180|X2=1050|Y2=180|X3=1050|Y3=170
|RECORD=27|IndexInSheet=147|OwnerPartId=-1|LineWidth=1|Color=8388608|LocationCount=2|X1=1040|Y1=790|X2=1190|Y2=790
|RECORD=27|IndexInSheet=148|OwnerPartId=-1|LineWidth=1|Color=8388608|LocationCount=2|X1=1060|Y1=850|X2=1190|Y2=850
|RECORD=27|IndexInSheet=149|OwnerPartId=-1|LineWidth=1|Color=8388608|LocationCount=2|X1=1070|Y1=660|X2=1190|Y2=660
|RECORD=27|IndexInSheet=150|OwnerPartId=-1|LineWidth=1|Color=8388608|LocationCount=2|X1=1070|Y1=700|X2=1190|Y2=700
|RECORD=27|IndexInSheet=151|OwnerPartId=-1|LineWidth=1|Color=8388608|LocationCount=2|X1=1070|Y1=740|X2=1190|Y2=740
|RECORD=27|IndexInSheet=152|OwnerPartId=-1|LineWidth=1|Color=8388608|LocationCount=2|X1=1070|Y1=820|X2=1190|Y2=820
|RECORD=27|IndexInSheet=153|OwnerPartId=-1|LineWidth=1|Color=8388608|LocationCount=2|X1=1110|Y1=650|X2=1190|Y2=650
|RECORD=27|IndexInSheet=154|OwnerPartId=-1|LineWidth=1|Color=8388608|LocationCount=2|X1=1110|Y1=690|X2=1190|Y2=690
|RECORD=27|IndexInSheet=155|OwnerPartId=-1|LineWidth=1|Color=8388608|LocationCount=2|X1=1110|Y1=730|X2=1190|Y2=730
|RECORD=27|IndexInSheet=156|OwnerPartId=-1|LineWidth=1|Color=8388608|LocationCount=2|X1=1110|Y1=780|X2=1190|Y2=780
|RECORD=27|IndexInSheet=157|OwnerPartId=-1|LineWidth=1|Color=8388608|LocationCount=2|X1=1110|Y1=810|X2=1190|Y2=810
|RECORD=27|IndexInSheet=158|OwnerPartId=-1|LineWidth=1|Color=8388608|LocationCount=2|X1=1060|Y1=910|X2=1060|Y2=920
|RECORD=41|IndexInSheet=159|OwnerPartId=-1|Color=8388608|FontID=1|IsHidden=T|Name=ConfigurationParameters|ReadOnlyState=1
|RECORD=41|IndexInSheet=160|OwnerPartId=-1|Color=8388608|FontID=1|IsHidden=T|Name=ConfiguratorName|ReadOnlyState=1
|RECORD=41|IndexInSheet=161|OwnerPartId=-1|Color=8388608|FontID=1|IsHidden=T|Name=VersionControl_RevNumber|ReadOnlyState=1
|RECORD=41|IndexInSheet=162|OwnerPartId=-1|Color=8388608|FontID=1|IsHidden=T|Name=IsUserConfigurable|ReadOnlyState=1
|RECORD=41|IndexInSheet=163|OwnerPartId=-1|Color=8388608|FontID=1|IsHidden=T|Name=VersionControl_ProjFolderRevNumber|ReadOnlyState=1
|RECORD=41|IndexInSheet=164|OwnerPartId=-1|Color=8388608|FontID=1|IsHidden=T|Name=SPICEModelCache|ReadOnlyState=1
|RECORD=41|IndexInSheet=165|OwnerPartId=-1|Color=8388608|FontID=1|IsHidden=T|Text=*|Name=CurrentTime|ReadOnlyState=1
|RECORD=41|IndexInSheet=166|OwnerPartId=-1|Color=8388608|FontID=1|IsHidden=T|Text=*|Name=CurrentDate|ReadOnlyState=1
|RECORD=41|IndexInSheet=167|OwnerPartId=-1|Color=8388608|FontID=1|IsHidden=T|Text=*|Name=Time|ReadOnlyState=1
|RECORD=41|IndexInSheet=168|OwnerPartId=-1|Color=8388608|FontID=1|IsHidden=T|Text=*|Name=Date|ReadOnlyState=1
|RECORD=41|IndexInSheet=169|OwnerPartId=-1|Color=8388608|FontID=1|IsHidden=T|Text=*|Name=DocumentFullPathAndName|ReadOnlyState=1
|RECORD=41|IndexInSheet=170|OwnerPartId=-1|Color=8388608|FontID=1|IsHidden=T|Text=*|Name=DocumentName|ReadOnlyState=1
|RECORD=41|IndexInSheet=171|OwnerPartId=-1|Color=8388608|FontID=1|IsHidden=T|Text=*|Name=ModifiedDate|ReadOnlyState=1
|RECORD=41|IndexInSheet=172|OwnerPartId=-1|Color=8388608|FontID=1|IsHidden=T|Text=*|Name=ApprovedBy|ReadOnlyState=1
|RECORD=41|IndexInSheet=173|OwnerPartId=-1|Color=8388608|FontID=1|IsHidden=T|Text=*|Name=CheckedBy|ReadOnlyState=1
|RECORD=41|IndexInSheet=174|OwnerPartId=-1|Color=8388608|FontID=1|IsHidden=T|Text=*|Name=Author|ReadOnlyState=1
|RECORD=41|IndexInSheet=175|OwnerPartId=-1|Color=8388608|FontID=1|IsHidden=T|Text=*|Name=CompanyName|ReadOnlyState=1
|RECORD=41|IndexInSheet=176|OwnerPartId=-1|Color=8388608|FontID=1|IsHidden=T|Text=*|Name=DrawnBy|ReadOnlyState=1
|RECORD=41|IndexInSheet=177|OwnerPartId=-1|Color=8388608|FontID=1|IsHidden=T|Text=*|Name=Engineer|ReadOnlyState=1
|RECORD=41|IndexInSheet=178|OwnerPartId=-1|Color=8388608|FontID=1|IsHidden=T|Text=*|Name=Organization|ReadOnlyState=1
|RECORD=41|IndexInSheet=179|OwnerPartId=-1|Color=8388608|FontID=1|IsHidden=T|Text=*|Name=Address1|ReadOnlyState=1
|RECORD=41|IndexInSheet=180|OwnerPartId=-1|Color=8388608|FontID=1|IsHidden=T|Text=*|Name=Address2|ReadOnlyState=1
|RECORD=41|IndexInSheet=181|OwnerPartId=-1|Color=8388608|FontID=1|IsHidden=T|Text=*|Name=Address3|ReadOnlyState=1
|RECORD=41|IndexInSheet=182|OwnerPartId=-1|Color=8388608|FontID=1|IsHidden=T|Text=*|Name=Address4|ReadOnlyState=1
|RECORD=41|IndexInSheet=183|OwnerPartId=-1|Color=8388608|FontID=1|IsHidden=T|Text=*|Name=Title|ReadOnlyState=1
|RECORD=41|IndexInSheet=184|OwnerPartId=-1|Color=8388608|FontID=1|IsHidden=T|Text=*|Name=DocumentNumber|ReadOnlyState=1
|RECORD=41|IndexInSheet=185|OwnerPartId=-1|Color=8388608|FontID=1|IsHidden=T|Text=*|Name=Revision|ReadOnlyState=1
|RECORD=41|IndexInSheet=186|OwnerPartId=-1|Color=8388608|FontID=1|IsHidden=T|Text=*|Name=SheetNumber|ReadOnlyState=1
|RECORD=41|IndexInSheet=187|OwnerPartId=-1|Color=8388608|FontID=1|IsHidden=T|Text=*|Name=SheetTotal|ReadOnlyState=1
|RECORD=41|IndexInSheet=188|OwnerPartId=-1|Color=8388608|FontID=1|IsHidden=T|Text=*|Name=Rule|ReadOnlyState=1
|RECORD=41|IndexInSheet=189|OwnerPartId=-1|Color=8388608|FontID=1|IsHidden=T|Text=*|Name=ImagePath|ReadOnlyState=1
|RECORD=41|IndexInSheet=190|OwnerPartId=-1|Color=8388608|FontID=1|IsHidden=T|Text=*|Name=ProjectName|ReadOnlyState=1
|RECORD=41|IndexInSheet=191|OwnerPartId=-1|Color=8388608|FontID=1|IsHidden=T|Text=*|Name=Application_BuildNumber|ReadOnlyState=1
|RECORD=1|LibReference=SMTC-TSM-105-01-X-X|ComponentDescription=0.025" SQ Post Header, Surface Mount, Vertical, -55 to 125 degC, 2.54 mm Pitch, 10-Pin, Male, RoHS|PartCount=2|DisplayModeCount=1|IndexInSheet=192|OwnerPartId=-1|Location.X=950|Location.Y=400|Orientation=3|CurrentPartId=1|LibraryPath=*|SourceLibraryName=Altium Content Vault|TargetFileName=*|AreaColor=11599871|Color=128|PartIDLocked=T|DesignItemId=CMP-1024-00233-1|AllPinCount=10
|RECORD=2|OwnerIndex=1053|OwnerPartId=1|FormalType=1|Electrical=4|PinConglomerate=50|PinLength=20|Location.X=910|Location.Y=380|Name=3|Designator=3|PinPropagationDelay=0.000000E+000
|RECORD=2|OwnerIndex=1053|OwnerPartId=1|FormalType=1|Electrical=4|PinConglomerate=48|PinLength=20|Location.X=950|Location.Y=390|Name=2|Designator=2|PinPropagationDelay=0.000000E+000
|RECORD=2|OwnerIndex=1053|OwnerPartId=1|FormalType=1|Electrical=4|PinConglomerate=50|PinLength=20|Location.X=910|Location.Y=390|Name=1|Designator=1|PinPropagationDelay=0.000000E+000
|RECORD=2|OwnerIndex=1053|OwnerPartId=1|FormalType=1|Electrical=4|PinConglomerate=48|PinLength=20|Location.X=950|Location.Y=380|Name=4|Designator=4|PinPropagationDelay=0.000000E+000
|RECORD=2|OwnerIndex=1053|OwnerPartId=1|FormalType=1|Electrical=4|PinConglomerate=50|PinLength=20|Location.X=910|Location.Y=370|Name=5|Designator=5|SwapIDPart=Ž&Ž1|PinPropagationDelay=0.000000E+000
|RECORD=2|OwnerIndex=1053|OwnerPartId=1|FormalType=1|Electrical=4|PinConglomerate=48|PinLength=20|Location.X=950|Location.Y=370|Name=6|Designator=6|SwapIDPart=Ž&Ž1|PinPropagationDelay=0.000000E+000
|RECORD=2|OwnerIndex=1053|OwnerPartId=1|FormalType=1|Electrical=4|PinConglomerate=50|PinLength=20|Location.X=910|Location.Y=360|Name=7|Designator=7|SwapIDPart=Ž&Ž1|PinPropagationDelay=0.000000E+000
|RECORD=2|OwnerIndex=1053|OwnerPartId=1|FormalType=1|Electrical=4|PinConglomerate=48|PinLength=20|Location.X=950|Location.Y=360|Name=8|Designator=8|SwapIDPart=Ž&Ž1|PinPropagationDelay=0.000000E+000
|RECORD=2|OwnerIndex=1053|OwnerPartId=1|FormalType=1|Electrical=4|PinConglomerate=50|PinLength=20|Location.X=910|Location.Y=350|Name=9|Designator=9|SwapIDPart=Ž&Ž1|PinPropagationDelay=0.000000E+000
|RECORD=2|OwnerIndex=1053|OwnerPartId=1|FormalType=1|Electrical=4|PinConglomerate=48|PinLength=20|Location.X=950|Location.Y=350|Name=10|Designator=10|SwapIDPart=Ž&Ž1|PinPropagationDelay=0.000000E+000
|RECORD=6|OwnerIndex=1053|IsNotAccesible=T|IndexInSheet=10|OwnerPartId=1|LineWidth=1|Color=16711680|LocationCount=2|X1=950|Y1=380|X2=943|Y2=380
|RECORD=8|OwnerIndex=1053|IsNotAccesible=T|IndexInSheet=11|OwnerPartId=1|Location.X=940|Location.Y=380|Radius=3|SecondaryRadius=3|LineWidth=1|Color=16711680|AreaColor=16711680|IsSolid=T
|RECORD=6|OwnerIndex=1053|IsNotAccesible=T|IndexInSheet=12|OwnerPartId=1|LineWidth=1|Color=16711680|LocationCount=2|X1=950|Y1=390|X2=943|Y2=390
|RECORD=8|OwnerIndex=1053|IsNotAccesible=T|IndexInSheet=13|OwnerPartId=1|Location.X=940|Location.Y=390|Radius=3|SecondaryRadius=3|LineWidth=1|Color=16711680|AreaColor=16711680|IsSolid=T
|RECORD=6|OwnerIndex=1053|IsNotAccesible=T|IndexInSheet=14|OwnerPartId=1|LineWidth=1|Color=16711680|LocationCount=2|X1=910|Y1=380|X2=917|Y2=380
|RECORD=8|OwnerIndex=1053|IsNotAccesible=T|IndexInSheet=15|OwnerPartId=1|Location.X=920|Location.Y=380|Radius=3|SecondaryRadius=3|LineWidth=1|Color=16711680|AreaColor=16711680|IsSolid=T
|RECORD=6|OwnerIndex=1053|IsNotAccesible=T|IndexInSheet=16|OwnerPartId=1|LineWidth=1|Color=16711680|LocationCount=2|X1=910|Y1=390|X2=917|Y2=390
|RECORD=8|OwnerIndex=1053|IsNotAccesible=T|IndexInSheet=17|OwnerPartId=1|Location.X=920|Location.Y=390|Radius=3|SecondaryRadius=3|LineWidth=1|Color=16711680|AreaColor=16711680|IsSolid=T
|RECORD=6|OwnerIndex=1053|IsNotAccesible=T|IndexInSheet=18|OwnerPartId=1|LineWidth=1|Color=16711680|LocationCount=5|X1=910|Y1=340|X2=950|Y2=340|X3=950|Y3=400|X4=910|Y4=400|X5=910|Y5=340
|RECORD=6|OwnerIndex=1053|IsNotAccesible=T|IndexInSheet=19|OwnerPartId=1|LineWidth=1|Color=16711680|LocationCount=2|X1=950|Y1=370|X2=943|Y2=370
|RECORD=8|OwnerIndex=1053|IsNotAccesible=T|IndexInSheet=20|OwnerPartId=1|Location.X=940|Location.Y=370|Radius=3|SecondaryRadius=3|LineWidth=1|Color=16711680|AreaColor=16711680|IsSolid=T
|RECORD=6|OwnerIndex=1053|IsNotAccesible=T|IndexInSheet=21|OwnerPartId=1|LineWidth=1|Color=16711680|LocationCount=2|X1=910|Y1=370|X2=917|Y2=370
|RECORD=8|OwnerIndex=1053|IsNotAccesible=T|IndexInSheet=22|OwnerPartId=1|Location.X=920|Location.Y=370|Radius=3|SecondaryRadius=3|LineWidth=1|Color=16711680|AreaColor=16711680|IsSolid=T
|RECORD=6|OwnerIndex=1053|IsNotAccesible=T|IndexInSheet=23|OwnerPartId=1|LineWidth=1|Color=16711680|LocationCount=2|X1=950|Y1=360|X2=943|Y2=360
|RECORD=8|OwnerIndex=1053|IsNotAccesible=T|IndexInSheet=24|OwnerPartId=1|Location.X=940|Location.Y=360|Radius=3|SecondaryRadius=3|LineWidth=1|Color=16711680|AreaColor=16711680|IsSolid=T
|RECORD=6|OwnerIndex=1053|IsNotAccesible=T|IndexInSheet=25|OwnerPartId=1|LineWidth=1|Color=16711680|LocationCount=2|X1=910|Y1=360|X2=917|Y2=360
|RECORD=8|OwnerIndex=1053|IsNotAccesible=T|IndexInSheet=26|OwnerPartId=1|Location.X=920|Location.Y=360|Radius=3|SecondaryRadius=3|LineWidth=1|Color=16711680|AreaColor=16711680|IsSolid=T
|RECORD=6|OwnerIndex=1053|IsNotAccesible=T|IndexInSheet=27|OwnerPartId=1|LineWidth=1|Color=16711680|LocationCount=2|X1=950|Y1=350|X2=943|Y2=350
|RECORD=8|OwnerIndex=1053|IsNotAccesible=T|IndexInSheet=28|OwnerPartId=1|Location.X=940|Location.Y=350|Radius=3|SecondaryRadius=3|LineWidth=1|Color=16711680|AreaColor=16711680|IsSolid=T
|RECORD=6|OwnerIndex=1053|IsNotAccesible=T|IndexInSheet=29|OwnerPartId=1|LineWidth=1|Color=16711680|LocationCount=2|X1=910|Y1=350|X2=917|Y2=350
|RECORD=8|OwnerIndex=1053|IsNotAccesible=T|IndexInSheet=30|OwnerPartId=1|Location.X=920|Location.Y=350|Radius=3|SecondaryRadius=3|LineWidth=1|Color=16711680|AreaColor=16711680|IsSolid=T
|RECORD=41|OwnerIndex=1053|IndexInSheet=31|OwnerPartId=-1|Location.X=888|Location.Y=401|Color=8388608|FontID=2|IsHidden=T|Text=http://www.samtec.com|Name=ComponentLink1URL
|RECORD=41|OwnerIndex=1053|IndexInSheet=32|OwnerPartId=-1|Location.X=888|Location.Y=401|Color=8388608|FontID=1|IsHidden=T|Text=F-214|Name=DatasheetVersion
|RECORD=41|OwnerIndex=1053|IndexInSheet=33|OwnerPartId=-1|Location.X=888|Location.Y=401|Color=8388608|FontID=2|IsHidden=T|Text=http://www.samtec.com/documents/webfiles/cpdf/TSM-1XX-XX-XXX-XX-X-XXX-X-MKT.pdf|Name=ComponentLink3URL
|RECORD=41|OwnerIndex=1053|IndexInSheet=34|OwnerPartId=-1|Location.X=888|Location.Y=401|Color=8388608|FontID=1|IsHidden=T|Text=-55 to 125 degC|Name=Temperature Range
|RECORD=41|OwnerIndex=1053|IndexInSheet=35|OwnerPartId=-1|Location.X=888|Location.Y=401|Color=8388608|FontID=1|IsHidden=T|Text=Double Row Gullwing ASM|Name=PackageDescription
|RECORD=41|OwnerIndex=1053|IndexInSheet=36|OwnerPartId=-1|Location.X=888|Location.Y=401|Color=8388608|FontID=1|IsHidden=T|Text=TSM-105-01-L-DV|Name=PartNumber
|RECORD=41|OwnerIndex=1053|IndexInSheet=37|OwnerPartId=-1|Location.X=888|Location.Y=401|Color=8388608|FontID=2|IsHidden=T|Text=http://www.samtec.com/documents/webfiles/pdf/TSM.PDF|Name=ComponentLink2URL
|RECORD=41|OwnerIndex=1053|IndexInSheet=38|OwnerPartId=-1|Location.X=888|Location.Y=401|Color=8388608|FontID=1|IsHidden=T|Text=2.54 mm|Name=Pitch
|RECORD=41|OwnerIndex=1053|IndexInSheet=39|OwnerPartId=-1|Location.X=888|Location.Y=401|Color=8388608|FontID=1|IsHidden=T|Text=Datasheet|Name=ComponentLink2Description
|RECORD=41|OwnerIndex=1053|IndexInSheet=40|OwnerPartId=-1|Location.X=888|Location.Y=401|Color=8388608|FontID=1|IsHidden=T|Text=Surface Mount|Name=Mounting Technology
|RECORD=41|OwnerIndex=1053|IndexInSheet=41|OwnerPartId=-1|Location.X=888|Location.Y=401|Color=8388608|FontID=1|IsHidden=T|Text=DJ, 4/1991|Name=PackageVersion
|RECORD=41|OwnerIndex=1053|IndexInSheet=42|OwnerPartId=-1|Location.X=888|Location.Y=401|Color=8388608|FontID=1|IsHidden=T|Text=True|Name=RoHS
|RECORD=41|OwnerIndex=1053|IndexInSheet=43|OwnerPartId=-1|Location.X=888|Location.Y=401|Color=8388608|FontID=1|IsHidden=T|Text=Package Specification|Name=ComponentLink3Description
|RECORD=41|OwnerIndex=1053|IndexInSheet=44|OwnerPartId=-1|Location.X=888|Location.Y=401|Color=8388608|FontID=1|IsHidden=T|Text=Samtec|Name=Manufacturer
|RECORD=41|OwnerIndex=1053|IndexInSheet=45|OwnerPartId=-1|Location.X=888|Location.Y=401|Color=8388608|FontID=1|IsHidden=T|Text=TSM-105-01-X-DV|Name=PackageReference
|RECORD=41|OwnerIndex=1053|IndexInSheet=46|OwnerPartId=-1|Location.X=888|Location.Y=401|Color=8388608|FontID=1|IsHidden=T|Text=Vertical|Name=Orientation
|RECORD=41|OwnerIndex=1053|IndexInSheet=47|OwnerPartId=-1|Location.X=888|Location.Y=401|Color=8388608|FontID=1|IsHidden=T|Text=Manufacturer URL|Name=ComponentLink1Description
|RECORD=34|OwnerIndex=1053|IndexInSheet=-1|OwnerPartId=-1|Location.X=909|Location.Y=401|Color=8388608|FontID=1|Text=P4|Name=Designator|ReadOnlyState=1
|RECORD=41|OwnerIndex=1053|IndexInSheet=-1|OwnerPartId=-1|Location.X=909|Location.Y=329|Color=8388608|FontID=1|Text=TSM-105-01-L-DV|Name=Comment
|RECORD=44|OwnerIndex=1053
|RECORD=45|OwnerIndex=1114|IndexInSheet=-1|Description=Double Row Gullwing ASM, 2x5 Pins, Vertical, 2.54mm Pitch, Male|UseComponentLibrary=T|ModelName=SMTC-TSM-105-01-X-DV|ModelType=PCBLIB|DatafileCount=1|ModelDatafileEntity0=SMTC-TSM-105-01-X-DV|ModelDatafileKind0=PCBLib|IsCurrent=T|DatalinksLocked=T|DatabaseDatalinksLocked=T
|RECORD=46|OwnerIndex=1115
|RECORD=48|OwnerIndex=1115
|RECORD=41|OwnerIndex=1117|IndexInSheet=-1|OwnerPartId=-1|Color=8388608|FontID=1|IsHidden=T|Text=2D|Name=Available Preview Images
|RECORD=27|IndexInSheet=193|OwnerPartId=-1|LineWidth=1|Color=8388608|LocationCount=4|X1=840|Y1=430|X2=880|Y2=430|X3=880|Y3=390|X4=890|Y4=390
|RECORD=27|IndexInSheet=194|OwnerPartId=-1|LineWidth=1|Color=8388608|LocationCount=4|X1=840|Y1=400|X2=870|Y2=400|X3=870|Y3=380|X4=890|Y4=380
|RECORD=27|IndexInSheet=195|OwnerPartId=-1|LineWidth=1|Color=8388608|LocationCount=2|X1=840|Y1=370|X2=890|Y2=370
|RECORD=27|IndexInSheet=196|OwnerPartId=-1|LineWidth=1|Color=8388608|LocationCount=4|X1=840|Y1=340|X2=870|Y2=340|X3=870|Y3=350|X4=890|Y4=350
|RECORD=27|IndexInSheet=197|OwnerPartId=-1|LineWidth=1|Color=8388608|LocationCount=2|X1=970|Y1=350|X2=1010|Y2=350
|RECORD=27|IndexInSheet=198|OwnerPartId=-1|LineWidth=1|Color=8388608|LocationCount=4|X1=970|Y1=370|X2=1030|Y2=370|X3=1030|Y3=380|X4=1030|Y4=410
|RECORD=27|IndexInSheet=199|OwnerPartId=-1|LineWidth=1|Color=8388608|LocationCount=2|X1=970|Y1=380|X2=1030|Y2=380
|RECORD=27|IndexInSheet=200|OwnerPartId=-1|LineWidth=1|Color=8388608|LocationCount=4|X1=970|Y1=390|X2=1010|Y2=390|X3=1010|Y3=350|X4=1010|Y4=330
|RECORD=29|IndexInSheet=-1|OwnerPartId=-1|Location.X=670|Location.Y=940|Color=128
|RECORD=29|IndexInSheet=-1|OwnerPartId=-1|Location.X=670|Location.Y=950|Color=128
|RECORD=29|IndexInSheet=-1|OwnerPartId=-1|Location.X=740|Location.Y=630|Color=128
|RECORD=29|IndexInSheet=-1|OwnerPartId=-1|Location.X=740|Location.Y=660|Color=128
|RECORD=29|IndexInSheet=-1|OwnerPartId=-1|Location.X=740|Location.Y=690|Color=128
|RECORD=29|IndexInSheet=-1|OwnerPartId=-1|Location.X=740|Location.Y=700|Color=128
|RECORD=29|IndexInSheet=-1|OwnerPartId=-1|Location.X=740|Location.Y=730|Color=128
|RECORD=29|IndexInSheet=-1|OwnerPartId=-1|Location.X=740|Location.Y=740|Color=128
|RECORD=29|IndexInSheet=-1|OwnerPartId=-1|Location.X=740|Location.Y=770|Color=128
|RECORD=29|IndexInSheet=-1|OwnerPartId=-1|Location.X=740|Location.Y=790|Color=128
|RECORD=29|IndexInSheet=-1|OwnerPartId=-1|Location.X=740|Location.Y=820|Color=128
|RECORD=29|IndexInSheet=-1|OwnerPartId=-1|Location.X=740|Location.Y=890|Color=128
|RECORD=29|IndexInSheet=-1|OwnerPartId=-1|Location.X=940|Location.Y=640|Color=128
|RECORD=29|IndexInSheet=-1|OwnerPartId=-1|Location.X=940|Location.Y=670|Color=128
|RECORD=29|IndexInSheet=-1|OwnerPartId=-1|Location.X=940|Location.Y=680|Color=128
|RECORD=29|IndexInSheet=-1|OwnerPartId=-1|Location.X=940|Location.Y=710|Color=128
|RECORD=29|IndexInSheet=-1|OwnerPartId=-1|Location.X=940|Location.Y=720|Color=128
|RECORD=29|IndexInSheet=-1|OwnerPartId=-1|Location.X=940|Location.Y=750|Color=128
|RECORD=29|IndexInSheet=-1|OwnerPartId=-1|Location.X=940|Location.Y=770|Color=128
|RECORD=29|IndexInSheet=-1|OwnerPartId=-1|Location.X=940|Location.Y=800|Color=128
|RECORD=29|IndexInSheet=-1|OwnerPartId=-1|Location.X=940|Location.Y=830|Color=128
|RECORD=29|IndexInSheet=-1|OwnerPartId=-1|Location.X=990|Location.Y=940|Color=128
|RECORD=29|IndexInSheet=-1|OwnerPartId=-1|Location.X=1010|Location.Y=350|Color=128
|RECORD=29|IndexInSheet=-1|OwnerPartId=-1|Location.X=1030|Location.Y=380|Color=128
|RECORD=29|IndexInSheet=-1|OwnerPartId=-1|Location.X=1030|Location.Y=870|Color=128
|RECORD=29|IndexInSheet=-1|OwnerPartId=-1|Location.X=1060|Location.Y=850|Color=128